(kicad_sch
	(version 20231120)
	(generator "eeschema")
	(generator_version "8.0")
	(paper "A3")
	(title_block
		(title "Jetson Orin Baseboard OCuLink Expansion")
		(date "2025-03-18")
		(rev "1.1.0")
		(company "Antmicro Ltd")
		(comment 1 "www.antmicro.com")
	)
	(junction
		(at 246.38 236.22)
		(diameter 0)
		(color 0 0 0 0)
	)
	(junction
		(at 267.97 271.78)
		(diameter 0)
		(color 0 0 0 0)
	)
	(junction
		(at 160.02 121.92)
		(diameter 0)
		(color 0 0 0 0)
	)
	(junction
		(at 289.56 166.37)
		(diameter 0)
		(color 0 0 0 0)
	)
	(junction
		(at 152.4 111.76)
		(diameter 0)
		(color 0 0 0 0)
	)
	(junction
		(at 262.89 257.81)
		(diameter 0)
		(color 0 0 0 0)
	)
	(junction
		(at 232.41 228.6)
		(diameter 0)
		(color 0 0 0 0)
	)
	(junction
		(at 267.97 250.19)
		(diameter 0)
		(color 0 0 0 0)
	)
	(junction
		(at 57.15 106.68)
		(diameter 0)
		(color 0 0 0 0)
	)
	(junction
		(at 198.12 257.81)
		(diameter 0)
		(color 0 0 0 0)
	)
	(junction
		(at 173.99 27.94)
		(diameter 0)
		(color 0 0 0 0)
	)
	(junction
		(at 154.94 114.3)
		(diameter 0)
		(color 0 0 0 0)
	)
	(junction
		(at 358.14 166.37)
		(diameter 0)
		(color 0 0 0 0)
	)
	(junction
		(at 57.15 124.46)
		(diameter 0)
		(color 0 0 0 0)
	)
	(junction
		(at 250.19 161.29)
		(diameter 0)
		(color 0 0 0 0)
	)
	(junction
		(at 257.81 166.37)
		(diameter 0)
		(color 0 0 0 0)
	)
	(junction
		(at 250.19 116.84)
		(diameter 0)
		(color 0 0 0 0)
	)
	(junction
		(at 224.79 124.46)
		(diameter 0)
		(color 0 0 0 0)
	)
	(junction
		(at 289.56 121.92)
		(diameter 0)
		(color 0 0 0 0)
	)
	(junction
		(at 224.79 121.92)
		(diameter 0)
		(color 0 0 0 0)
	)
	(junction
		(at 152.4 133.35)
		(diameter 0)
		(color 0 0 0 0)
	)
	(junction
		(at 257.81 121.92)
		(diameter 0)
		(color 0 0 0 0)
	)
	(junction
		(at 165.1 43.18)
		(diameter 0)
		(color 0 0 0 0)
	)
	(junction
		(at 177.8 82.55)
		(diameter 0)
		(color 0 0 0 0)
	)
	(junction
		(at 163.83 180.34)
		(diameter 0)
		(color 0 0 0 0)
	)
	(junction
		(at 149.86 133.35)
		(diameter 0)
		(color 0 0 0 0)
	)
	(junction
		(at 73.66 33.02)
		(diameter 0)
		(color 0 0 0 0)
	)
	(junction
		(at 265.43 252.73)
		(diameter 0)
		(color 0 0 0 0)
	)
	(junction
		(at 321.31 45.72)
		(diameter 0)
		(color 0 0 0 0)
	)
	(junction
		(at 147.32 27.94)
		(diameter 0)
		(color 0 0 0 0)
	)
	(junction
		(at 173.99 97.79)
		(diameter 0)
		(color 0 0 0 0)
	)
	(junction
		(at 193.04 87.63)
		(diameter 0)
		(color 0 0 0 0)
	)
	(junction
		(at 35.56 129.54)
		(diameter 0)
		(color 0 0 0 0)
	)
	(junction
		(at 57.15 45.72)
		(diameter 0)
		(color 0 0 0 0)
	)
	(junction
		(at 198.12 262.89)
		(diameter 0)
		(color 0 0 0 0)
	)
	(junction
		(at 181.61 165.1)
		(diameter 0)
		(color 0 0 0 0)
	)
	(junction
		(at 152.4 99.06)
		(diameter 0)
		(color 0 0 0 0)
	)
	(junction
		(at 260.35 271.78)
		(diameter 0)
		(color 0 0 0 0)
	)
	(junction
		(at 57.15 60.96)
		(diameter 0)
		(color 0 0 0 0)
	)
	(junction
		(at 35.56 121.92)
		(diameter 0)
		(color 0 0 0 0)
	)
	(junction
		(at 57.15 91.44)
		(diameter 0)
		(color 0 0 0 0)
	)
	(junction
		(at 172.72 165.1)
		(diameter 0)
		(color 0 0 0 0)
	)
	(junction
		(at 154.94 99.06)
		(diameter 0)
		(color 0 0 0 0)
	)
	(junction
		(at 154.94 165.1)
		(diameter 0)
		(color 0 0 0 0)
	)
	(junction
		(at 73.66 55.88)
		(diameter 0)
		(color 0 0 0 0)
	)
	(junction
		(at 182.88 43.18)
		(diameter 0)
		(color 0 0 0 0)
	)
	(junction
		(at 157.48 99.06)
		(diameter 0)
		(color 0 0 0 0)
	)
	(junction
		(at 57.15 53.34)
		(diameter 0)
		(color 0 0 0 0)
	)
	(junction
		(at 180.34 80.01)
		(diameter 0)
		(color 0 0 0 0)
	)
	(junction
		(at 54.61 129.54)
		(diameter 0)
		(color 0 0 0 0)
	)
	(junction
		(at 270.51 271.78)
		(diameter 0)
		(color 0 0 0 0)
	)
	(junction
		(at 265.43 237.49)
		(diameter 0)
		(color 0 0 0 0)
	)
	(junction
		(at 172.72 180.34)
		(diameter 0)
		(color 0 0 0 0)
	)
	(junction
		(at 182.88 27.94)
		(diameter 0)
		(color 0 0 0 0)
	)
	(junction
		(at 181.61 180.34)
		(diameter 0)
		(color 0 0 0 0)
	)
	(junction
		(at 345.44 156.21)
		(diameter 0)
		(color 0 0 0 0)
	)
	(junction
		(at 373.38 132.08)
		(diameter 0)
		(color 0 0 0 0)
	)
	(junction
		(at 190.5 90.17)
		(diameter 0)
		(color 0 0 0 0)
	)
	(junction
		(at 318.77 68.58)
		(diameter 0)
		(color 0 0 0 0)
	)
	(junction
		(at 270.51 237.49)
		(diameter 0)
		(color 0 0 0 0)
	)
	(junction
		(at 73.66 40.64)
		(diameter 0)
		(color 0 0 0 0)
	)
	(junction
		(at 57.15 76.2)
		(diameter 0)
		(color 0 0 0 0)
	)
	(junction
		(at 44.45 129.54)
		(diameter 0)
		(color 0 0 0 0)
	)
	(junction
		(at 73.66 63.5)
		(diameter 0)
		(color 0 0 0 0)
	)
	(junction
		(at 242.57 218.44)
		(diameter 0)
		(color 0 0 0 0)
	)
	(junction
		(at 73.66 48.26)
		(diameter 0)
		(color 0 0 0 0)
	)
	(junction
		(at 298.45 121.92)
		(diameter 0)
		(color 0 0 0 0)
	)
	(junction
		(at 189.23 180.34)
		(diameter 0)
		(color 0 0 0 0)
	)
	(junction
		(at 73.66 91.44)
		(diameter 0)
		(color 0 0 0 0)
	)
	(junction
		(at 339.09 40.64)
		(diameter 0)
		(color 0 0 0 0)
	)
	(junction
		(at 73.66 76.2)
		(diameter 0)
		(color 0 0 0 0)
	)
	(junction
		(at 260.35 237.49)
		(diameter 0)
		(color 0 0 0 0)
	)
	(junction
		(at 260.35 260.35)
		(diameter 0)
		(color 0 0 0 0)
	)
	(junction
		(at 262.89 237.49)
		(diameter 0)
		(color 0 0 0 0)
	)
	(junction
		(at 54.61 114.3)
		(diameter 0)
		(color 0 0 0 0)
	)
	(junction
		(at 35.56 114.3)
		(diameter 0)
		(color 0 0 0 0)
	)
	(junction
		(at 73.66 106.68)
		(diameter 0)
		(color 0 0 0 0)
	)
	(junction
		(at 243.84 210.82)
		(diameter 0)
		(color 0 0 0 0)
	)
	(junction
		(at 157.48 119.38)
		(diameter 0)
		(color 0 0 0 0)
	)
	(junction
		(at 157.48 133.35)
		(diameter 0)
		(color 0 0 0 0)
	)
	(junction
		(at 345.44 166.37)
		(diameter 0)
		(color 0 0 0 0)
	)
	(junction
		(at 73.66 119.38)
		(diameter 0)
		(color 0 0 0 0)
	)
	(junction
		(at 57.15 38.1)
		(diameter 0)
		(color 0 0 0 0)
	)
	(junction
		(at 73.66 124.46)
		(diameter 0)
		(color 0 0 0 0)
	)
	(junction
		(at 156.21 43.18)
		(diameter 0)
		(color 0 0 0 0)
	)
	(junction
		(at 149.86 109.22)
		(diameter 0)
		(color 0 0 0 0)
	)
	(junction
		(at 245.11 220.98)
		(diameter 0)
		(color 0 0 0 0)
	)
	(junction
		(at 257.81 262.89)
		(diameter 0)
		(color 0 0 0 0)
	)
	(junction
		(at 162.56 124.46)
		(diameter 0)
		(color 0 0 0 0)
	)
	(junction
		(at 229.87 226.06)
		(diameter 0)
		(color 0 0 0 0)
	)
	(junction
		(at 149.86 99.06)
		(diameter 0)
		(color 0 0 0 0)
	)
	(junction
		(at 154.94 133.35)
		(diameter 0)
		(color 0 0 0 0)
	)
	(junction
		(at 198.12 260.35)
		(diameter 0)
		(color 0 0 0 0)
	)
	(junction
		(at 165.1 27.94)
		(diameter 0)
		(color 0 0 0 0)
	)
	(junction
		(at 179.07 72.39)
		(diameter 0)
		(color 0 0 0 0)
	)
	(junction
		(at 160.02 133.35)
		(diameter 0)
		(color 0 0 0 0)
	)
	(junction
		(at 156.21 27.94)
		(diameter 0)
		(color 0 0 0 0)
	)
	(junction
		(at 163.83 165.1)
		(diameter 0)
		(color 0 0 0 0)
	)
	(junction
		(at 44.45 121.92)
		(diameter 0)
		(color 0 0 0 0)
	)
	(junction
		(at 173.99 43.18)
		(diameter 0)
		(color 0 0 0 0)
	)
	(junction
		(at 146.05 165.1)
		(diameter 0)
		(color 0 0 0 0)
	)
	(junction
		(at 298.45 166.37)
		(diameter 0)
		(color 0 0 0 0)
	)
	(junction
		(at 242.57 161.29)
		(diameter 0)
		(color 0 0 0 0)
	)
	(junction
		(at 194.31 43.18)
		(diameter 0)
		(color 0 0 0 0)
	)
	(junction
		(at 57.15 30.48)
		(diameter 0)
		(color 0 0 0 0)
	)
	(junction
		(at 270.51 247.65)
		(diameter 0)
		(color 0 0 0 0)
	)
	(junction
		(at 160.02 99.06)
		(diameter 0)
		(color 0 0 0 0)
	)
	(junction
		(at 57.15 119.38)
		(diameter 0)
		(color 0 0 0 0)
	)
	(junction
		(at 265.43 271.78)
		(diameter 0)
		(color 0 0 0 0)
	)
	(junction
		(at 358.14 156.21)
		(diameter 0)
		(color 0 0 0 0)
	)
	(junction
		(at 262.89 271.78)
		(diameter 0)
		(color 0 0 0 0)
	)
	(junction
		(at 321.31 43.18)
		(diameter 0)
		(color 0 0 0 0)
	)
	(junction
		(at 267.97 237.49)
		(diameter 0)
		(color 0 0 0 0)
	)
	(junction
		(at 242.57 116.84)
		(diameter 0)
		(color 0 0 0 0)
	)
	(junction
		(at 154.94 180.34)
		(diameter 0)
		(color 0 0 0 0)
	)
	(junction
		(at 44.45 114.3)
		(diameter 0)
		(color 0 0 0 0)
	)
	(no_connect
		(at 223.52 116.84)
	)
	(no_connect
		(at 71.12 104.14)
	)
	(no_connect
		(at 344.17 93.98)
	)
	(no_connect
		(at 223.52 81.28)
	)
	(no_connect
		(at 222.25 224.79)
	)
	(no_connect
		(at 59.69 104.14)
	)
	(no_connect
		(at 71.12 111.76)
	)
	(no_connect
		(at 71.12 73.66)
	)
	(no_connect
		(at 199.39 217.17)
	)
	(no_connect
		(at 59.69 78.74)
	)
	(no_connect
		(at 59.69 66.04)
	)
	(no_connect
		(at 71.12 83.82)
	)
	(no_connect
		(at 71.12 78.74)
	)
	(no_connect
		(at 71.12 96.52)
	)
	(no_connect
		(at 71.12 116.84)
	)
	(no_connect
		(at 71.12 101.6)
	)
	(no_connect
		(at 59.69 101.6)
	)
	(no_connect
		(at 71.12 81.28)
	)
	(no_connect
		(at 223.52 88.9)
	)
	(no_connect
		(at 71.12 99.06)
	)
	(no_connect
		(at 71.12 86.36)
	)
	(no_connect
		(at 71.12 68.58)
	)
	(no_connect
		(at 59.69 68.58)
	)
	(no_connect
		(at 223.52 86.36)
	)
	(no_connect
		(at 71.12 71.12)
	)
	(no_connect
		(at 59.69 88.9)
	)
	(no_connect
		(at 59.69 96.52)
	)
	(no_connect
		(at 223.52 78.74)
	)
	(no_connect
		(at 59.69 81.28)
	)
	(no_connect
		(at 71.12 53.34)
	)
	(no_connect
		(at 59.69 55.88)
	)
	(no_connect
		(at 71.12 114.3)
	)
	(no_connect
		(at 344.17 121.92)
	)
	(no_connect
		(at 71.12 58.42)
	)
	(no_connect
		(at 222.25 219.71)
	)
	(no_connect
		(at 71.12 109.22)
	)
	(no_connect
		(at 71.12 127)
	)
	(no_connect
		(at 222.25 217.17)
	)
	(no_connect
		(at 344.17 99.06)
	)
	(no_connect
		(at 199.39 219.71)
	)
	(no_connect
		(at 200.66 86.36)
	)
	(no_connect
		(at 71.12 129.54)
	)
	(no_connect
		(at 344.17 124.46)
	)
	(no_connect
		(at 71.12 121.92)
	)
	(no_connect
		(at 59.69 58.42)
	)
	(no_connect
		(at 222.25 227.33)
	)
	(no_connect
		(at 200.66 88.9)
	)
	(no_connect
		(at 71.12 60.96)
	)
	(no_connect
		(at 71.12 66.04)
	)
	(no_connect
		(at 344.17 101.6)
	)
	(no_connect
		(at 344.17 129.54)
	)
	(no_connect
		(at 200.66 78.74)
	)
	(no_connect
		(at 344.17 91.44)
	)
	(no_connect
		(at 199.39 224.79)
	)
	(no_connect
		(at 59.69 93.98)
	)
	(no_connect
		(at 59.69 86.36)
	)
	(no_connect
		(at 71.12 88.9)
	)
	(no_connect
		(at 344.17 132.08)
	)
	(no_connect
		(at 59.69 99.06)
	)
	(no_connect
		(at 71.12 93.98)
	)
	(no_connect
		(at 59.69 83.82)
	)
	(no_connect
		(at 71.12 50.8)
	)
	(no_connect
		(at 199.39 227.33)
	)
	(no_connect
		(at 200.66 81.28)
	)
	(wire
		(pts
			(xy 33.02 114.3) (xy 35.56 114.3)
		)
		(stroke
			(width 0)
			(type default)
		)
	)
	(wire
		(pts
			(xy 242.57 210.82) (xy 243.84 210.82)
		)
		(stroke
			(width 0)
			(type default)
		)
	)
	(wire
		(pts
			(xy 198.12 101.6) (xy 200.66 101.6)
		)
		(stroke
			(width 0)
			(type default)
		)
	)
	(wire
		(pts
			(xy 228.6 180.34) (xy 228.6 196.85)
		)
		(stroke
			(width 0)
			(type default)
		)
	)
	(wire
		(pts
			(xy 198.12 257.81) (xy 199.39 257.81)
		)
		(stroke
			(width 0)
			(type default)
		)
	)
	(wire
		(pts
			(xy 181.61 180.34) (xy 189.23 180.34)
		)
		(stroke
			(width 0)
			(type default)
		)
	)
	(wire
		(pts
			(xy 262.89 245.11) (xy 262.89 257.81)
		)
		(stroke
			(width 0)
			(type default)
		)
	)
	(wire
		(pts
			(xy 44.45 33.02) (xy 59.69 33.02)
		)
		(stroke
			(width 0)
			(type default)
		)
	)
	(wire
		(pts
			(xy 57.15 38.1) (xy 59.69 38.1)
		)
		(stroke
			(width 0)
			(type default)
		)
	)
	(wire
		(pts
			(xy 73.66 33.02) (xy 73.66 40.64)
		)
		(stroke
			(width 0)
			(type default)
		)
	)
	(wire
		(pts
			(xy 35.56 111.76) (xy 35.56 114.3)
		)
		(stroke
			(width 0)
			(type default)
		)
	)
	(wire
		(pts
			(xy 328.93 53.34) (xy 344.17 53.34)
		)
		(stroke
			(width 0)
			(type default)
		)
	)
	(wire
		(pts
			(xy 193.04 80.01) (xy 193.04 87.63)
		)
		(stroke
			(width 0)
			(type default)
		)
	)
	(wire
		(pts
			(xy 163.83 165.1) (xy 154.94 165.1)
		)
		(stroke
			(width 0)
			(type default)
		)
	)
	(wire
		(pts
			(xy 257.81 116.84) (xy 257.81 121.92)
		)
		(stroke
			(width 0)
			(type default)
		)
	)
	(wire
		(pts
			(xy 193.04 80.01) (xy 180.34 80.01)
		)
		(stroke
			(width 0)
			(type default)
		)
	)
	(wire
		(pts
			(xy 48.26 109.22) (xy 59.69 109.22)
		)
		(stroke
			(width 0)
			(type default)
		)
	)
	(wire
		(pts
			(xy 154.94 180.34) (xy 146.05 180.34)
		)
		(stroke
			(width 0)
			(type default)
		)
	)
	(wire
		(pts
			(xy 44.45 43.18) (xy 59.69 43.18)
		)
		(stroke
			(width 0)
			(type default)
		)
	)
	(wire
		(pts
			(xy 73.66 63.5) (xy 73.66 76.2)
		)
		(stroke
			(width 0)
			(type default)
		)
	)
	(wire
		(pts
			(xy 173.99 29.21) (xy 173.99 27.94)
		)
		(stroke
			(width 0)
			(type default)
		)
	)
	(wire
		(pts
			(xy 59.69 30.48) (xy 57.15 30.48)
		)
		(stroke
			(width 0)
			(type default)
		)
	)
	(wire
		(pts
			(xy 345.44 166.37) (xy 345.44 163.83)
		)
		(stroke
			(width 0)
			(type default)
		)
	)
	(wire
		(pts
			(xy 364.49 203.2) (xy 364.49 198.12)
		)
		(stroke
			(width 0)
			(type default)
		)
	)
	(wire
		(pts
			(xy 236.22 212.09) (xy 222.25 212.09)
		)
		(stroke
			(width 0)
			(type default)
		)
	)
	(wire
		(pts
			(xy 304.8 68.58) (xy 318.77 68.58)
		)
		(stroke
			(width 0)
			(type default)
		)
	)
	(wire
		(pts
			(xy 71.12 119.38) (xy 73.66 119.38)
		)
		(stroke
			(width 0)
			(type default)
		)
	)
	(wire
		(pts
			(xy 242.57 217.17) (xy 242.57 218.44)
		)
		(stroke
			(width 0)
			(type default)
		)
	)
	(wire
		(pts
			(xy 260.35 260.35) (xy 260.35 264.16)
		)
		(stroke
			(width 0)
			(type default)
		)
	)
	(wire
		(pts
			(xy 152.4 111.76) (xy 152.4 125.73)
		)
		(stroke
			(width 0)
			(type default)
		)
	)
	(wire
		(pts
			(xy 73.66 55.88) (xy 73.66 48.26)
		)
		(stroke
			(width 0)
			(type default)
		)
	)
	(wire
		(pts
			(xy 328.93 198.12) (xy 332.74 198.12)
		)
		(stroke
			(width 0)
			(type default)
		)
	)
	(wire
		(pts
			(xy 304.8 50.8) (xy 323.85 50.8)
		)
		(stroke
			(width 0)
			(type default)
		)
	)
	(wire
		(pts
			(xy 260.35 168.91) (xy 250.19 168.91)
		)
		(stroke
			(width 0)
			(type default)
		)
	)
	(wire
		(pts
			(xy 198.12 262.89) (xy 198.12 265.43)
		)
		(stroke
			(width 0)
			(type default)
		)
	)
	(wire
		(pts
			(xy 250.19 116.84) (xy 257.81 116.84)
		)
		(stroke
			(width 0)
			(type default)
		)
	)
	(wire
		(pts
			(xy 270.51 245.11) (xy 270.51 247.65)
		)
		(stroke
			(width 0)
			(type default)
		)
	)
	(wire
		(pts
			(xy 54.61 129.54) (xy 59.69 129.54)
		)
		(stroke
			(width 0)
			(type default)
		)
	)
	(wire
		(pts
			(xy 199.39 209.55) (xy 177.8 209.55)
		)
		(stroke
			(width 0)
			(type default)
		)
	)
	(wire
		(pts
			(xy 232.41 220.98) (xy 232.41 228.6)
		)
		(stroke
			(width 0)
			(type default)
		)
	)
	(wire
		(pts
			(xy 265.43 237.49) (xy 265.43 240.03)
		)
		(stroke
			(width 0)
			(type default)
		)
	)
	(wire
		(pts
			(xy 149.86 109.22) (xy 149.86 125.73)
		)
		(stroke
			(width 0)
			(type default)
		)
	)
	(wire
		(pts
			(xy 149.86 99.06) (xy 149.86 101.6)
		)
		(stroke
			(width 0)
			(type default)
		)
	)
	(wire
		(pts
			(xy 173.99 90.17) (xy 173.99 91.44)
		)
		(stroke
			(width 0)
			(type default)
		)
	)
	(wire
		(pts
			(xy 170.18 204.47) (xy 149.86 204.47)
		)
		(stroke
			(width 0)
			(type default)
		)
	)
	(wire
		(pts
			(xy 43.18 63.5) (xy 59.69 63.5)
		)
		(stroke
			(width 0)
			(type default)
		)
	)
	(wire
		(pts
			(xy 260.35 245.11) (xy 260.35 260.35)
		)
		(stroke
			(width 0)
			(type default)
		)
	)
	(wire
		(pts
			(xy 194.31 27.94) (xy 194.31 43.18)
		)
		(stroke
			(width 0)
			(type default)
		)
	)
	(wire
		(pts
			(xy 330.2 60.96) (xy 344.17 60.96)
		)
		(stroke
			(width 0)
			(type default)
		)
	)
	(wire
		(pts
			(xy 59.69 114.3) (xy 54.61 114.3)
		)
		(stroke
			(width 0)
			(type default)
		)
	)
	(wire
		(pts
			(xy 358.14 156.21) (xy 358.14 158.75)
		)
		(stroke
			(width 0)
			(type default)
		)
	)
	(wire
		(pts
			(xy 160.02 121.92) (xy 160.02 125.73)
		)
		(stroke
			(width 0)
			(type default)
		)
	)
	(wire
		(pts
			(xy 265.43 252.73) (xy 265.43 264.16)
		)
		(stroke
			(width 0)
			(type default)
		)
	)
	(wire
		(pts
			(xy 48.26 111.76) (xy 59.69 111.76)
		)
		(stroke
			(width 0)
			(type default)
		)
	)
	(wire
		(pts
			(xy 281.94 175.26) (xy 281.94 176.53)
		)
		(stroke
			(width 0)
			(type default)
		)
	)
	(wire
		(pts
			(xy 57.15 53.34) (xy 57.15 60.96)
		)
		(stroke
			(width 0)
			(type default)
		)
	)
	(wire
		(pts
			(xy 229.87 226.06) (xy 229.87 232.41)
		)
		(stroke
			(width 0)
			(type default)
		)
	)
	(wire
		(pts
			(xy 175.26 212.09) (xy 199.39 212.09)
		)
		(stroke
			(width 0)
			(type default)
		)
	)
	(wire
		(pts
			(xy 375.92 195.58) (xy 360.68 195.58)
		)
		(stroke
			(width 0)
			(type default)
		)
	)
	(wire
		(pts
			(xy 186.69 71.12) (xy 200.66 71.12)
		)
		(stroke
			(width 0)
			(type default)
		)
	)
	(wire
		(pts
			(xy 173.99 43.18) (xy 182.88 43.18)
		)
		(stroke
			(width 0)
			(type default)
		)
	)
	(wire
		(pts
			(xy 71.12 43.18) (xy 86.36 43.18)
		)
		(stroke
			(width 0)
			(type default)
		)
	)
	(wire
		(pts
			(xy 179.07 71.12) (xy 179.07 72.39)
		)
		(stroke
			(width 0)
			(type default)
		)
	)
	(wire
		(pts
			(xy 222.25 252.73) (xy 265.43 252.73)
		)
		(stroke
			(width 0)
			(type default)
		)
	)
	(wire
		(pts
			(xy 242.57 123.19) (xy 242.57 124.46)
		)
		(stroke
			(width 0)
			(type default)
		)
	)
	(wire
		(pts
			(xy 172.72 165.1) (xy 163.83 165.1)
		)
		(stroke
			(width 0)
			(type default)
		)
	)
	(wire
		(pts
			(xy 250.19 66.04) (xy 273.05 66.04)
		)
		(stroke
			(width 0)
			(type default)
		)
	)
	(wire
		(pts
			(xy 57.15 45.72) (xy 57.15 38.1)
		)
		(stroke
			(width 0)
			(type default)
		)
	)
	(wire
		(pts
			(xy 146.05 163.83) (xy 146.05 165.1)
		)
		(stroke
			(width 0)
			(type default)
		)
	)
	(wire
		(pts
			(xy 149.86 201.93) (xy 172.72 201.93)
		)
		(stroke
			(width 0)
			(type default)
		)
	)
	(wire
		(pts
			(xy 163.83 180.34) (xy 163.83 182.88)
		)
		(stroke
			(width 0)
			(type default)
		)
	)
	(wire
		(pts
			(xy 243.84 210.82) (xy 245.11 210.82)
		)
		(stroke
			(width 0)
			(type default)
		)
	)
	(wire
		(pts
			(xy 35.56 121.92) (xy 44.45 121.92)
		)
		(stroke
			(width 0)
			(type default)
		)
	)
	(wire
		(pts
			(xy 336.55 166.37) (xy 336.55 163.83)
		)
		(stroke
			(width 0)
			(type default)
		)
	)
	(wire
		(pts
			(xy 57.15 91.44) (xy 59.69 91.44)
		)
		(stroke
			(width 0)
			(type default)
		)
	)
	(wire
		(pts
			(xy 262.89 269.24) (xy 262.89 271.78)
		)
		(stroke
			(width 0)
			(type default)
		)
	)
	(wire
		(pts
			(xy 71.12 63.5) (xy 73.66 63.5)
		)
		(stroke
			(width 0)
			(type default)
		)
	)
	(wire
		(pts
			(xy 147.32 43.18) (xy 156.21 43.18)
		)
		(stroke
			(width 0)
			(type default)
		)
	)
	(wire
		(pts
			(xy 330.2 109.22) (xy 344.17 109.22)
		)
		(stroke
			(width 0)
			(type default)
		)
	)
	(wire
		(pts
			(xy 180.34 80.01) (xy 171.45 80.01)
		)
		(stroke
			(width 0)
			(type default)
		)
	)
	(wire
		(pts
			(xy 198.12 262.89) (xy 199.39 262.89)
		)
		(stroke
			(width 0)
			(type default)
		)
	)
	(wire
		(pts
			(xy 160.02 106.68) (xy 160.02 121.92)
		)
		(stroke
			(width 0)
			(type default)
		)
	)
	(wire
		(pts
			(xy 43.18 73.66) (xy 59.69 73.66)
		)
		(stroke
			(width 0)
			(type default)
		)
	)
	(wire
		(pts
			(xy 257.81 121.92) (xy 260.35 121.92)
		)
		(stroke
			(width 0)
			(type default)
		)
	)
	(wire
		(pts
			(xy 262.89 257.81) (xy 262.89 264.16)
		)
		(stroke
			(width 0)
			(type default)
		)
	)
	(wire
		(pts
			(xy 330.2 83.82) (xy 344.17 83.82)
		)
		(stroke
			(width 0)
			(type default)
		)
	)
	(wire
		(pts
			(xy 45.72 50.8) (xy 59.69 50.8)
		)
		(stroke
			(width 0)
			(type default)
		)
	)
	(wire
		(pts
			(xy 242.57 218.44) (xy 251.46 218.44)
		)
		(stroke
			(width 0)
			(type default)
		)
	)
	(wire
		(pts
			(xy 298.45 125.73) (xy 298.45 121.92)
		)
		(stroke
			(width 0)
			(type default)
		)
	)
	(wire
		(pts
			(xy 304.8 53.34) (xy 323.85 53.34)
		)
		(stroke
			(width 0)
			(type default)
		)
	)
	(wire
		(pts
			(xy 149.86 99.06) (xy 147.32 99.06)
		)
		(stroke
			(width 0)
			(type default)
		)
	)
	(wire
		(pts
			(xy 243.84 209.55) (xy 243.84 210.82)
		)
		(stroke
			(width 0)
			(type default)
		)
	)
	(wire
		(pts
			(xy 242.57 167.64) (xy 242.57 168.91)
		)
		(stroke
			(width 0)
			(type default)
		)
	)
	(wire
		(pts
			(xy 328.93 207.01) (xy 328.93 210.82)
		)
		(stroke
			(width 0)
			(type default)
		)
	)
	(wire
		(pts
			(xy 321.31 43.18) (xy 321.31 45.72)
		)
		(stroke
			(width 0)
			(type default)
		)
	)
	(wire
		(pts
			(xy 364.49 190.5) (xy 360.68 190.5)
		)
		(stroke
			(width 0)
			(type default)
		)
	)
	(wire
		(pts
			(xy 44.45 40.64) (xy 59.69 40.64)
		)
		(stroke
			(width 0)
			(type default)
		)
	)
	(wire
		(pts
			(xy 257.81 237.49) (xy 257.81 240.03)
		)
		(stroke
			(width 0)
			(type default)
		)
	)
	(wire
		(pts
			(xy 386.08 196.85) (xy 386.08 203.2)
		)
		(stroke
			(width 0)
			(type default)
		)
	)
	(wire
		(pts
			(xy 157.48 99.06) (xy 157.48 101.6)
		)
		(stroke
			(width 0)
			(type default)
		)
	)
	(wire
		(pts
			(xy 330.2 66.04) (xy 344.17 66.04)
		)
		(stroke
			(width 0)
			(type default)
		)
	)
	(wire
		(pts
			(xy 44.45 129.54) (xy 54.61 129.54)
		)
		(stroke
			(width 0)
			(type default)
		)
	)
	(wire
		(pts
			(xy 165.1 27.94) (xy 173.99 27.94)
		)
		(stroke
			(width 0)
			(type default)
		)
	)
	(wire
		(pts
			(xy 162.56 106.68) (xy 162.56 124.46)
		)
		(stroke
			(width 0)
			(type default)
		)
	)
	(wire
		(pts
			(xy 260.35 269.24) (xy 260.35 271.78)
		)
		(stroke
			(width 0)
			(type default)
		)
	)
	(wire
		(pts
			(xy 149.86 130.81) (xy 149.86 133.35)
		)
		(stroke
			(width 0)
			(type default)
		)
	)
	(wire
		(pts
			(xy 182.88 27.94) (xy 182.88 29.21)
		)
		(stroke
			(width 0)
			(type default)
		)
	)
	(wire
		(pts
			(xy 242.57 161.29) (xy 242.57 162.56)
		)
		(stroke
			(width 0)
			(type default)
		)
	)
	(wire
		(pts
			(xy 160.02 99.06) (xy 157.48 99.06)
		)
		(stroke
			(width 0)
			(type default)
		)
	)
	(wire
		(pts
			(xy 330.2 86.36) (xy 344.17 86.36)
		)
		(stroke
			(width 0)
			(type default)
		)
	)
	(wire
		(pts
			(xy 222.25 247.65) (xy 270.51 247.65)
		)
		(stroke
			(width 0)
			(type default)
		)
	)
	(wire
		(pts
			(xy 265.43 271.78) (xy 262.89 271.78)
		)
		(stroke
			(width 0)
			(type default)
		)
	)
	(wire
		(pts
			(xy 54.61 129.54) (xy 54.61 127)
		)
		(stroke
			(width 0)
			(type default)
		)
	)
	(wire
		(pts
			(xy 179.07 99.06) (xy 179.07 97.79)
		)
		(stroke
			(width 0)
			(type default)
		)
	)
	(wire
		(pts
			(xy 157.48 99.06) (xy 154.94 99.06)
		)
		(stroke
			(width 0)
			(type default)
		)
	)
	(wire
		(pts
			(xy 181.61 165.1) (xy 181.61 167.64)
		)
		(stroke
			(width 0)
			(type default)
		)
	)
	(wire
		(pts
			(xy 339.09 38.1) (xy 339.09 40.64)
		)
		(stroke
			(width 0)
			(type default)
		)
	)
	(wire
		(pts
			(xy 162.56 124.46) (xy 200.66 124.46)
		)
		(stroke
			(width 0)
			(type default)
		)
	)
	(wire
		(pts
			(xy 57.15 76.2) (xy 59.69 76.2)
		)
		(stroke
			(width 0)
			(type default)
		)
	)
	(wire
		(pts
			(xy 73.66 106.68) (xy 73.66 119.38)
		)
		(stroke
			(width 0)
			(type default)
		)
	)
	(wire
		(pts
			(xy 154.94 165.1) (xy 146.05 165.1)
		)
		(stroke
			(width 0)
			(type default)
		)
	)
	(wire
		(pts
			(xy 35.56 129.54) (xy 44.45 129.54)
		)
		(stroke
			(width 0)
			(type default)
		)
	)
	(wire
		(pts
			(xy 57.15 119.38) (xy 57.15 124.46)
		)
		(stroke
			(width 0)
			(type default)
		)
	)
	(wire
		(pts
			(xy 189.23 180.34) (xy 228.6 180.34)
		)
		(stroke
			(width 0)
			(type default)
		)
	)
	(wire
		(pts
			(xy 222.25 262.89) (xy 257.81 262.89)
		)
		(stroke
			(width 0)
			(type default)
		)
	)
	(wire
		(pts
			(xy 367.03 156.21) (xy 358.14 156.21)
		)
		(stroke
			(width 0)
			(type default)
		)
	)
	(wire
		(pts
			(xy 160.02 99.06) (xy 160.02 101.6)
		)
		(stroke
			(width 0)
			(type default)
		)
	)
	(wire
		(pts
			(xy 270.51 237.49) (xy 273.05 237.49)
		)
		(stroke
			(width 0)
			(type default)
		)
	)
	(wire
		(pts
			(xy 59.69 60.96) (xy 57.15 60.96)
		)
		(stroke
			(width 0)
			(type default)
		)
	)
	(wire
		(pts
			(xy 367.03 163.83) (xy 367.03 166.37)
		)
		(stroke
			(width 0)
			(type default)
		)
	)
	(wire
		(pts
			(xy 171.45 82.55) (xy 177.8 82.55)
		)
		(stroke
			(width 0)
			(type default)
		)
	)
	(wire
		(pts
			(xy 250.19 124.46) (xy 250.19 123.19)
		)
		(stroke
			(width 0)
			(type default)
		)
	)
	(wire
		(pts
			(xy 330.2 78.74) (xy 344.17 78.74)
		)
		(stroke
			(width 0)
			(type default)
		)
	)
	(wire
		(pts
			(xy 157.48 133.35) (xy 160.02 133.35)
		)
		(stroke
			(width 0)
			(type default)
		)
	)
	(wire
		(pts
			(xy 59.69 121.92) (xy 44.45 121.92)
		)
		(stroke
			(width 0)
			(type default)
		)
	)
	(wire
		(pts
			(xy 172.72 165.1) (xy 172.72 167.64)
		)
		(stroke
			(width 0)
			(type default)
		)
	)
	(wire
		(pts
			(xy 57.15 106.68) (xy 59.69 106.68)
		)
		(stroke
			(width 0)
			(type default)
		)
	)
	(wire
		(pts
			(xy 330.2 114.3) (xy 344.17 114.3)
		)
		(stroke
			(width 0)
			(type default)
		)
	)
	(wire
		(pts
			(xy 339.09 40.64) (xy 344.17 40.64)
		)
		(stroke
			(width 0)
			(type default)
		)
	)
	(wire
		(pts
			(xy 54.61 127) (xy 59.69 127)
		)
		(stroke
			(width 0)
			(type default)
		)
	)
	(wire
		(pts
			(xy 179.07 99.06) (xy 200.66 99.06)
		)
		(stroke
			(width 0)
			(type default)
		)
	)
	(wire
		(pts
			(xy 373.38 137.16) (xy 373.38 132.08)
		)
		(stroke
			(width 0)
			(type default)
		)
	)
	(wire
		(pts
			(xy 223.52 71.12) (xy 247.65 71.12)
		)
		(stroke
			(width 0)
			(type default)
		)
	)
	(wire
		(pts
			(xy 181.61 165.1) (xy 172.72 165.1)
		)
		(stroke
			(width 0)
			(type default)
		)
	)
	(wire
		(pts
			(xy 33.02 121.92) (xy 35.56 121.92)
		)
		(stroke
			(width 0)
			(type default)
		)
	)
	(wire
		(pts
			(xy 257.81 262.89) (xy 257.81 264.16)
		)
		(stroke
			(width 0)
			(type default)
		)
	)
	(wire
		(pts
			(xy 262.89 271.78) (xy 260.35 271.78)
		)
		(stroke
			(width 0)
			(type default)
		)
	)
	(wire
		(pts
			(xy 328.93 71.12) (xy 344.17 71.12)
		)
		(stroke
			(width 0)
			(type default)
		)
	)
	(wire
		(pts
			(xy 344.17 224.79) (xy 340.36 224.79)
		)
		(stroke
			(width 0)
			(type default)
		)
	)
	(wire
		(pts
			(xy 245.11 212.09) (xy 245.11 210.82)
		)
		(stroke
			(width 0)
			(type default)
		)
	)
	(wire
		(pts
			(xy 149.86 209.55) (xy 172.72 209.55)
		)
		(stroke
			(width 0)
			(type default)
		)
	)
	(wire
		(pts
			(xy 224.79 119.38) (xy 224.79 121.92)
		)
		(stroke
			(width 0)
			(type default)
		)
	)
	(wire
		(pts
			(xy 147.32 96.52) (xy 147.32 99.06)
		)
		(stroke
			(width 0)
			(type default)
		)
	)
	(wire
		(pts
			(xy 190.5 82.55) (xy 190.5 90.17)
		)
		(stroke
			(width 0)
			(type default)
		)
	)
	(wire
		(pts
			(xy 250.19 73.66) (xy 273.05 73.66)
		)
		(stroke
			(width 0)
			(type default)
		)
	)
	(wire
		(pts
			(xy 257.81 166.37) (xy 260.35 166.37)
		)
		(stroke
			(width 0)
			(type default)
		)
	)
	(wire
		(pts
			(xy 256.54 218.44) (xy 270.51 218.44)
		)
		(stroke
			(width 0)
			(type default)
		)
	)
	(wire
		(pts
			(xy 298.45 166.37) (xy 303.53 166.37)
		)
		(stroke
			(width 0)
			(type default)
		)
	)
	(wire
		(pts
			(xy 229.87 99.06) (xy 231.14 99.06)
		)
		(stroke
			(width 0)
			(type default)
		)
	)
	(wire
		(pts
			(xy 59.69 53.34) (xy 57.15 53.34)
		)
		(stroke
			(width 0)
			(type default)
		)
	)
	(wire
		(pts
			(xy 181.61 180.34) (xy 181.61 182.88)
		)
		(stroke
			(width 0)
			(type default)
		)
	)
	(wire
		(pts
			(xy 71.12 35.56) (xy 86.36 35.56)
		)
		(stroke
			(width 0)
			(type default)
		)
	)
	(wire
		(pts
			(xy 154.94 106.68) (xy 154.94 114.3)
		)
		(stroke
			(width 0)
			(type default)
		)
	)
	(wire
		(pts
			(xy 71.12 45.72) (xy 86.36 45.72)
		)
		(stroke
			(width 0)
			(type default)
		)
	)
	(wire
		(pts
			(xy 330.2 106.68) (xy 344.17 106.68)
		)
		(stroke
			(width 0)
			(type default)
		)
	)
	(wire
		(pts
			(xy 245.11 220.98) (xy 251.46 220.98)
		)
		(stroke
			(width 0)
			(type default)
		)
	)
	(wire
		(pts
			(xy 321.31 43.18) (xy 344.17 43.18)
		)
		(stroke
			(width 0)
			(type default)
		)
	)
	(wire
		(pts
			(xy 73.66 124.46) (xy 73.66 132.08)
		)
		(stroke
			(width 0)
			(type default)
		)
	)
	(wire
		(pts
			(xy 396.24 196.85) (xy 396.24 203.2)
		)
		(stroke
			(width 0)
			(type default)
		)
	)
	(wire
		(pts
			(xy 250.19 161.29) (xy 250.19 162.56)
		)
		(stroke
			(width 0)
			(type default)
		)
	)
	(wire
		(pts
			(xy 257.81 166.37) (xy 257.81 171.45)
		)
		(stroke
			(width 0)
			(type default)
		)
	)
	(wire
		(pts
			(xy 224.79 124.46) (xy 224.79 127)
		)
		(stroke
			(width 0)
			(type default)
		)
	)
	(wire
		(pts
			(xy 198.12 257.81) (xy 198.12 260.35)
		)
		(stroke
			(width 0)
			(type default)
		)
	)
	(wire
		(pts
			(xy 160.02 121.92) (xy 200.66 121.92)
		)
		(stroke
			(width 0)
			(type default)
		)
	)
	(wire
		(pts
			(xy 154.94 99.06) (xy 154.94 101.6)
		)
		(stroke
			(width 0)
			(type default)
		)
	)
	(wire
		(pts
			(xy 152.4 99.06) (xy 149.86 99.06)
		)
		(stroke
			(width 0)
			(type default)
		)
	)
	(wire
		(pts
			(xy 175.26 204.47) (xy 199.39 204.47)
		)
		(stroke
			(width 0)
			(type default)
		)
	)
	(wire
		(pts
			(xy 234.95 236.22) (xy 246.38 236.22)
		)
		(stroke
			(width 0)
			(type default)
		)
	)
	(wire
		(pts
			(xy 222.25 257.81) (xy 262.89 257.81)
		)
		(stroke
			(width 0)
			(type default)
		)
	)
	(wire
		(pts
			(xy 276.86 127) (xy 276.86 132.08)
		)
		(stroke
			(width 0)
			(type default)
		)
	)
	(wire
		(pts
			(xy 337.82 40.64) (xy 339.09 40.64)
		)
		(stroke
			(width 0)
			(type default)
		)
	)
	(wire
		(pts
			(xy 289.56 121.92) (xy 289.56 125.73)
		)
		(stroke
			(width 0)
			(type default)
		)
	)
	(wire
		(pts
			(xy 71.12 30.48) (xy 73.66 30.48)
		)
		(stroke
			(width 0)
			(type default)
		)
	)
	(wire
		(pts
			(xy 246.38 234.95) (xy 246.38 236.22)
		)
		(stroke
			(width 0)
			(type default)
		)
	)
	(wire
		(pts
			(xy 182.88 43.18) (xy 182.88 44.45)
		)
		(stroke
			(width 0)
			(type default)
		)
	)
	(wire
		(pts
			(xy 57.15 53.34) (xy 57.15 45.72)
		)
		(stroke
			(width 0)
			(type default)
		)
	)
	(wire
		(pts
			(xy 177.8 73.66) (xy 177.8 72.39)
		)
		(stroke
			(width 0)
			(type default)
		)
	)
	(wire
		(pts
			(xy 298.45 130.81) (xy 298.45 132.08)
		)
		(stroke
			(width 0)
			(type default)
		)
	)
	(wire
		(pts
			(xy 260.35 237.49) (xy 260.35 240.03)
		)
		(stroke
			(width 0)
			(type default)
		)
	)
	(wire
		(pts
			(xy 154.94 99.06) (xy 152.4 99.06)
		)
		(stroke
			(width 0)
			(type default)
		)
	)
	(wire
		(pts
			(xy 190.5 90.17) (xy 190.5 96.52)
		)
		(stroke
			(width 0)
			(type default)
		)
	)
	(wire
		(pts
			(xy 223.52 73.66) (xy 245.11 73.66)
		)
		(stroke
			(width 0)
			(type default)
		)
	)
	(wire
		(pts
			(xy 57.15 60.96) (xy 57.15 76.2)
		)
		(stroke
			(width 0)
			(type default)
		)
	)
	(wire
		(pts
			(xy 224.79 119.38) (xy 223.52 119.38)
		)
		(stroke
			(width 0)
			(type default)
		)
	)
	(wire
		(pts
			(xy 44.45 121.92) (xy 44.45 120.65)
		)
		(stroke
			(width 0)
			(type default)
		)
	)
	(wire
		(pts
			(xy 250.19 168.91) (xy 250.19 167.64)
		)
		(stroke
			(width 0)
			(type default)
		)
	)
	(wire
		(pts
			(xy 156.21 27.94) (xy 165.1 27.94)
		)
		(stroke
			(width 0)
			(type default)
		)
	)
	(wire
		(pts
			(xy 152.4 130.81) (xy 152.4 133.35)
		)
		(stroke
			(width 0)
			(type default)
		)
	)
	(wire
		(pts
			(xy 396.24 187.96) (xy 396.24 191.77)
		)
		(stroke
			(width 0)
			(type default)
		)
	)
	(wire
		(pts
			(xy 165.1 43.18) (xy 165.1 44.45)
		)
		(stroke
			(width 0)
			(type default)
		)
	)
	(wire
		(pts
			(xy 71.12 106.68) (xy 73.66 106.68)
		)
		(stroke
			(width 0)
			(type default)
		)
	)
	(wire
		(pts
			(xy 173.99 97.79) (xy 173.99 99.06)
		)
		(stroke
			(width 0)
			(type default)
		)
	)
	(wire
		(pts
			(xy 194.31 43.18) (xy 194.31 58.42)
		)
		(stroke
			(width 0)
			(type default)
		)
	)
	(wire
		(pts
			(xy 186.69 63.5) (xy 200.66 63.5)
		)
		(stroke
			(width 0)
			(type default)
		)
	)
	(wire
		(pts
			(xy 332.74 190.5) (xy 328.93 190.5)
		)
		(stroke
			(width 0)
			(type default)
		)
	)
	(wire
		(pts
			(xy 35.56 120.65) (xy 35.56 121.92)
		)
		(stroke
			(width 0)
			(type default)
		)
	)
	(wire
		(pts
			(xy 231.14 99.06) (xy 231.14 97.79)
		)
		(stroke
			(width 0)
			(type default)
		)
	)
	(wire
		(pts
			(xy 149.86 133.35) (xy 152.4 133.35)
		)
		(stroke
			(width 0)
			(type default)
		)
	)
	(wire
		(pts
			(xy 250.19 161.29) (xy 242.57 161.29)
		)
		(stroke
			(width 0)
			(type default)
		)
	)
	(wire
		(pts
			(xy 316.23 195.58) (xy 332.74 195.58)
		)
		(stroke
			(width 0)
			(type default)
		)
	)
	(wire
		(pts
			(xy 328.93 201.93) (xy 328.93 198.12)
		)
		(stroke
			(width 0)
			(type default)
		)
	)
	(wire
		(pts
			(xy 71.12 40.64) (xy 73.66 40.64)
		)
		(stroke
			(width 0)
			(type default)
		)
	)
	(wire
		(pts
			(xy 275.59 171.45) (xy 276.86 171.45)
		)
		(stroke
			(width 0)
			(type default)
		)
	)
	(wire
		(pts
			(xy 156.21 43.18) (xy 156.21 44.45)
		)
		(stroke
			(width 0)
			(type default)
		)
	)
	(wire
		(pts
			(xy 57.15 106.68) (xy 57.15 119.38)
		)
		(stroke
			(width 0)
			(type default)
		)
	)
	(wire
		(pts
			(xy 246.38 242.57) (xy 246.38 243.84)
		)
		(stroke
			(width 0)
			(type default)
		)
	)
	(wire
		(pts
			(xy 236.22 204.47) (xy 222.25 204.47)
		)
		(stroke
			(width 0)
			(type default)
		)
	)
	(wire
		(pts
			(xy 173.99 27.94) (xy 182.88 27.94)
		)
		(stroke
			(width 0)
			(type default)
		)
	)
	(wire
		(pts
			(xy 147.32 27.94) (xy 156.21 27.94)
		)
		(stroke
			(width 0)
			(type default)
		)
	)
	(wire
		(pts
			(xy 173.99 96.52) (xy 173.99 97.79)
		)
		(stroke
			(width 0)
			(type default)
		)
	)
	(wire
		(pts
			(xy 44.45 35.56) (xy 59.69 35.56)
		)
		(stroke
			(width 0)
			(type default)
		)
	)
	(wire
		(pts
			(xy 57.15 30.48) (xy 57.15 38.1)
		)
		(stroke
			(width 0)
			(type default)
		)
	)
	(wire
		(pts
			(xy 246.38 228.6) (xy 246.38 229.87)
		)
		(stroke
			(width 0)
			(type default)
		)
	)
	(wire
		(pts
			(xy 267.97 245.11) (xy 267.97 250.19)
		)
		(stroke
			(width 0)
			(type default)
		)
	)
	(wire
		(pts
			(xy 73.66 30.48) (xy 73.66 33.02)
		)
		(stroke
			(width 0)
			(type default)
		)
	)
	(wire
		(pts
			(xy 224.79 240.03) (xy 222.25 240.03)
		)
		(stroke
			(width 0)
			(type default)
		)
	)
	(wire
		(pts
			(xy 147.32 43.18) (xy 147.32 44.45)
		)
		(stroke
			(width 0)
			(type default)
		)
	)
	(wire
		(pts
			(xy 267.97 250.19) (xy 267.97 264.16)
		)
		(stroke
			(width 0)
			(type default)
		)
	)
	(wire
		(pts
			(xy 154.94 165.1) (xy 154.94 167.64)
		)
		(stroke
			(width 0)
			(type default)
		)
	)
	(wire
		(pts
			(xy 172.72 180.34) (xy 163.83 180.34)
		)
		(stroke
			(width 0)
			(type default)
		)
	)
	(wire
		(pts
			(xy 358.14 168.91) (xy 358.14 166.37)
		)
		(stroke
			(width 0)
			(type default)
		)
	)
	(wire
		(pts
			(xy 364.49 187.96) (xy 364.49 190.5)
		)
		(stroke
			(width 0)
			(type default)
		)
	)
	(wire
		(pts
			(xy 154.94 114.3) (xy 154.94 125.73)
		)
		(stroke
			(width 0)
			(type default)
		)
	)
	(wire
		(pts
			(xy 369.57 129.54) (xy 373.38 129.54)
		)
		(stroke
			(width 0)
			(type default)
		)
	)
	(wire
		(pts
			(xy 71.12 76.2) (xy 73.66 76.2)
		)
		(stroke
			(width 0)
			(type default)
		)
	)
	(wire
		(pts
			(xy 267.97 237.49) (xy 267.97 240.03)
		)
		(stroke
			(width 0)
			(type default)
		)
	)
	(wire
		(pts
			(xy 318.77 68.58) (xy 323.85 68.58)
		)
		(stroke
			(width 0)
			(type default)
		)
	)
	(wire
		(pts
			(xy 163.83 165.1) (xy 163.83 167.64)
		)
		(stroke
			(width 0)
			(type default)
		)
	)
	(wire
		(pts
			(xy 146.05 180.34) (xy 146.05 182.88)
		)
		(stroke
			(width 0)
			(type default)
		)
	)
	(wire
		(pts
			(xy 224.79 124.46) (xy 223.52 124.46)
		)
		(stroke
			(width 0)
			(type default)
		)
	)
	(wire
		(pts
			(xy 198.12 104.14) (xy 200.66 104.14)
		)
		(stroke
			(width 0)
			(type default)
		)
	)
	(wire
		(pts
			(xy 154.94 114.3) (xy 200.66 114.3)
		)
		(stroke
			(width 0)
			(type default)
		)
	)
	(wire
		(pts
			(xy 223.52 93.98) (xy 234.95 93.98)
		)
		(stroke
			(width 0)
			(type default)
		)
	)
	(wire
		(pts
			(xy 223.52 99.06) (xy 224.79 99.06)
		)
		(stroke
			(width 0)
			(type default)
		)
	)
	(wire
		(pts
			(xy 257.81 269.24) (xy 257.81 271.78)
		)
		(stroke
			(width 0)
			(type default)
		)
	)
	(wire
		(pts
			(xy 73.66 76.2) (xy 73.66 91.44)
		)
		(stroke
			(width 0)
			(type default)
		)
	)
	(wire
		(pts
			(xy 71.12 124.46) (xy 73.66 124.46)
		)
		(stroke
			(width 0)
			(type default)
		)
	)
	(wire
		(pts
			(xy 182.88 27.94) (xy 194.31 27.94)
		)
		(stroke
			(width 0)
			(type default)
		)
	)
	(wire
		(pts
			(xy 386.08 187.96) (xy 386.08 191.77)
		)
		(stroke
			(width 0)
			(type default)
		)
	)
	(wire
		(pts
			(xy 73.66 40.64) (xy 73.66 48.26)
		)
		(stroke
			(width 0)
			(type default)
		)
	)
	(wire
		(pts
			(xy 54.61 116.84) (xy 59.69 116.84)
		)
		(stroke
			(width 0)
			(type default)
		)
	)
	(wire
		(pts
			(xy 190.5 90.17) (xy 189.23 90.17)
		)
		(stroke
			(width 0)
			(type default)
		)
	)
	(wire
		(pts
			(xy 330.2 58.42) (xy 344.17 58.42)
		)
		(stroke
			(width 0)
			(type default)
		)
	)
	(wire
		(pts
			(xy 222.25 260.35) (xy 260.35 260.35)
		)
		(stroke
			(width 0)
			(type default)
		)
	)
	(wire
		(pts
			(xy 33.02 129.54) (xy 35.56 129.54)
		)
		(stroke
			(width 0)
			(type default)
		)
	)
	(wire
		(pts
			(xy 199.39 255.27) (xy 198.12 255.27)
		)
		(stroke
			(width 0)
			(type default)
		)
	)
	(wire
		(pts
			(xy 170.18 212.09) (xy 149.86 212.09)
		)
		(stroke
			(width 0)
			(type default)
		)
	)
	(wire
		(pts
			(xy 358.14 163.83) (xy 358.14 166.37)
		)
		(stroke
			(width 0)
			(type default)
		)
	)
	(wire
		(pts
			(xy 224.79 242.57) (xy 222.25 242.57)
		)
		(stroke
			(width 0)
			(type default)
		)
	)
	(wire
		(pts
			(xy 229.87 218.44) (xy 242.57 218.44)
		)
		(stroke
			(width 0)
			(type default)
		)
	)
	(wire
		(pts
			(xy 71.12 91.44) (xy 73.66 91.44)
		)
		(stroke
			(width 0)
			(type default)
		)
	)
	(wire
		(pts
			(xy 345.44 168.91) (xy 345.44 166.37)
		)
		(stroke
			(width 0)
			(type default)
		)
	)
	(wire
		(pts
			(xy 180.34 73.66) (xy 180.34 72.39)
		)
		(stroke
			(width 0)
			(type default)
		)
	)
	(wire
		(pts
			(xy 289.56 121.92) (xy 298.45 121.92)
		)
		(stroke
			(width 0)
			(type default)
		)
	)
	(wire
		(pts
			(xy 265.43 269.24) (xy 265.43 271.78)
		)
		(stroke
			(width 0)
			(type default)
		)
	)
	(wire
		(pts
			(xy 157.48 106.68) (xy 157.48 119.38)
		)
		(stroke
			(width 0)
			(type default)
		)
	)
	(wire
		(pts
			(xy 281.94 124.46) (xy 281.94 125.73)
		)
		(stroke
			(width 0)
			(type default)
		)
	)
	(wire
		(pts
			(xy 250.19 116.84) (xy 250.19 118.11)
		)
		(stroke
			(width 0)
			(type default)
		)
	)
	(wire
		(pts
			(xy 193.04 237.49) (xy 191.77 237.49)
		)
		(stroke
			(width 0)
			(type default)
		)
	)
	(wire
		(pts
			(xy 181.61 180.34) (xy 172.72 180.34)
		)
		(stroke
			(width 0)
			(type default)
		)
	)
	(wire
		(pts
			(xy 186.69 73.66) (xy 200.66 73.66)
		)
		(stroke
			(width 0)
			(type default)
		)
	)
	(wire
		(pts
			(xy 298.45 121.92) (xy 303.53 121.92)
		)
		(stroke
			(width 0)
			(type default)
		)
	)
	(wire
		(pts
			(xy 304.8 71.12) (xy 323.85 71.12)
		)
		(stroke
			(width 0)
			(type default)
		)
	)
	(wire
		(pts
			(xy 156.21 43.18) (xy 165.1 43.18)
		)
		(stroke
			(width 0)
			(type default)
		)
	)
	(wire
		(pts
			(xy 224.79 121.92) (xy 224.79 124.46)
		)
		(stroke
			(width 0)
			(type default)
		)
	)
	(wire
		(pts
			(xy 165.1 27.94) (xy 165.1 29.21)
		)
		(stroke
			(width 0)
			(type default)
		)
	)
	(wire
		(pts
			(xy 234.95 236.22) (xy 234.95 237.49)
		)
		(stroke
			(width 0)
			(type default)
		)
	)
	(wire
		(pts
			(xy 336.55 156.21) (xy 345.44 156.21)
		)
		(stroke
			(width 0)
			(type default)
		)
	)
	(wire
		(pts
			(xy 146.05 165.1) (xy 146.05 167.64)
		)
		(stroke
			(width 0)
			(type default)
		)
	)
	(wire
		(pts
			(xy 236.22 209.55) (xy 222.25 209.55)
		)
		(stroke
			(width 0)
			(type default)
		)
	)
	(wire
		(pts
			(xy 57.15 119.38) (xy 59.69 119.38)
		)
		(stroke
			(width 0)
			(type default)
		)
	)
	(wire
		(pts
			(xy 345.44 154.94) (xy 345.44 156.21)
		)
		(stroke
			(width 0)
			(type default)
		)
	)
	(wire
		(pts
			(xy 242.57 161.29) (xy 242.57 160.02)
		)
		(stroke
			(width 0)
			(type default)
		)
	)
	(wire
		(pts
			(xy 157.48 119.38) (xy 200.66 119.38)
		)
		(stroke
			(width 0)
			(type default)
		)
	)
	(wire
		(pts
			(xy 275.59 124.46) (xy 281.94 124.46)
		)
		(stroke
			(width 0)
			(type default)
		)
	)
	(wire
		(pts
			(xy 71.12 55.88) (xy 73.66 55.88)
		)
		(stroke
			(width 0)
			(type default)
		)
	)
	(wire
		(pts
			(xy 147.32 27.94) (xy 147.32 29.21)
		)
		(stroke
			(width 0)
			(type default)
		)
	)
	(wire
		(pts
			(xy 313.69 121.92) (xy 313.69 120.65)
		)
		(stroke
			(width 0)
			(type default)
		)
	)
	(wire
		(pts
			(xy 289.56 175.26) (xy 289.56 176.53)
		)
		(stroke
			(width 0)
			(type default)
		)
	)
	(wire
		(pts
			(xy 246.38 236.22) (xy 246.38 237.49)
		)
		(stroke
			(width 0)
			(type default)
		)
	)
	(wire
		(pts
			(xy 318.77 78.74) (xy 318.77 80.01)
		)
		(stroke
			(width 0)
			(type default)
		)
	)
	(wire
		(pts
			(xy 191.77 237.49) (xy 191.77 236.22)
		)
		(stroke
			(width 0)
			(type default)
		)
	)
	(wire
		(pts
			(xy 262.89 237.49) (xy 265.43 237.49)
		)
		(stroke
			(width 0)
			(type default)
		)
	)
	(wire
		(pts
			(xy 229.87 226.06) (xy 233.68 226.06)
		)
		(stroke
			(width 0)
			(type default)
		)
	)
	(wire
		(pts
			(xy 252.73 71.12) (xy 273.05 71.12)
		)
		(stroke
			(width 0)
			(type default)
		)
	)
	(wire
		(pts
			(xy 345.44 156.21) (xy 345.44 158.75)
		)
		(stroke
			(width 0)
			(type default)
		)
	)
	(wire
		(pts
			(xy 163.83 180.34) (xy 154.94 180.34)
		)
		(stroke
			(width 0)
			(type default)
		)
	)
	(wire
		(pts
			(xy 190.5 82.55) (xy 177.8 82.55)
		)
		(stroke
			(width 0)
			(type default)
		)
	)
	(wire
		(pts
			(xy 223.52 66.04) (xy 245.11 66.04)
		)
		(stroke
			(width 0)
			(type default)
		)
	)
	(wire
		(pts
			(xy 267.97 271.78) (xy 265.43 271.78)
		)
		(stroke
			(width 0)
			(type default)
		)
	)
	(wire
		(pts
			(xy 321.31 38.1) (xy 321.31 43.18)
		)
		(stroke
			(width 0)
			(type default)
		)
	)
	(wire
		(pts
			(xy 252.73 63.5) (xy 273.05 63.5)
		)
		(stroke
			(width 0)
			(type default)
		)
	)
	(wire
		(pts
			(xy 57.15 29.21) (xy 57.15 30.48)
		)
		(stroke
			(width 0)
			(type default)
		)
	)
	(wire
		(pts
			(xy 44.45 114.3) (xy 54.61 114.3)
		)
		(stroke
			(width 0)
			(type default)
		)
	)
	(wire
		(pts
			(xy 73.66 119.38) (xy 73.66 124.46)
		)
		(stroke
			(width 0)
			(type default)
		)
	)
	(wire
		(pts
			(xy 173.99 43.18) (xy 173.99 44.45)
		)
		(stroke
			(width 0)
			(type default)
		)
	)
	(wire
		(pts
			(xy 316.23 193.04) (xy 332.74 193.04)
		)
		(stroke
			(width 0)
			(type default)
		)
	)
	(wire
		(pts
			(xy 57.15 124.46) (xy 57.15 132.08)
		)
		(stroke
			(width 0)
			(type default)
		)
	)
	(wire
		(pts
			(xy 232.41 220.98) (xy 245.11 220.98)
		)
		(stroke
			(width 0)
			(type default)
		)
	)
	(wire
		(pts
			(xy 275.59 168.91) (xy 281.94 168.91)
		)
		(stroke
			(width 0)
			(type default)
		)
	)
	(wire
		(pts
			(xy 45.72 48.26) (xy 59.69 48.26)
		)
		(stroke
			(width 0)
			(type default)
		)
	)
	(wire
		(pts
			(xy 276.86 171.45) (xy 276.86 176.53)
		)
		(stroke
			(width 0)
			(type default)
		)
	)
	(wire
		(pts
			(xy 222.25 250.19) (xy 267.97 250.19)
		)
		(stroke
			(width 0)
			(type default)
		)
	)
	(wire
		(pts
			(xy 198.12 260.35) (xy 198.12 262.89)
		)
		(stroke
			(width 0)
			(type default)
		)
	)
	(wire
		(pts
			(xy 250.19 161.29) (xy 257.81 161.29)
		)
		(stroke
			(width 0)
			(type default)
		)
	)
	(wire
		(pts
			(xy 270.51 271.78) (xy 267.97 271.78)
		)
		(stroke
			(width 0)
			(type default)
		)
	)
	(wire
		(pts
			(xy 181.61 165.1) (xy 189.23 165.1)
		)
		(stroke
			(width 0)
			(type default)
		)
	)
	(wire
		(pts
			(xy 345.44 243.84) (xy 345.44 241.3)
		)
		(stroke
			(width 0)
			(type default)
		)
	)
	(wire
		(pts
			(xy 270.51 247.65) (xy 270.51 264.16)
		)
		(stroke
			(width 0)
			(type default)
		)
	)
	(wire
		(pts
			(xy 180.34 72.39) (xy 179.07 72.39)
		)
		(stroke
			(width 0)
			(type default)
		)
	)
	(wire
		(pts
			(xy 152.4 106.68) (xy 152.4 111.76)
		)
		(stroke
			(width 0)
			(type default)
		)
	)
	(wire
		(pts
			(xy 267.97 269.24) (xy 267.97 271.78)
		)
		(stroke
			(width 0)
			(type default)
		)
	)
	(wire
		(pts
			(xy 194.31 58.42) (xy 200.66 58.42)
		)
		(stroke
			(width 0)
			(type default)
		)
	)
	(wire
		(pts
			(xy 222.25 196.85) (xy 228.6 196.85)
		)
		(stroke
			(width 0)
			(type default)
		)
	)
	(wire
		(pts
			(xy 160.02 130.81) (xy 160.02 133.35)
		)
		(stroke
			(width 0)
			(type default)
		)
	)
	(wire
		(pts
			(xy 179.07 97.79) (xy 173.99 97.79)
		)
		(stroke
			(width 0)
			(type default)
		)
	)
	(wire
		(pts
			(xy 367.03 158.75) (xy 367.03 156.21)
		)
		(stroke
			(width 0)
			(type default)
		)
	)
	(wire
		(pts
			(xy 270.51 237.49) (xy 270.51 240.03)
		)
		(stroke
			(width 0)
			(type default)
		)
	)
	(wire
		(pts
			(xy 330.2 76.2) (xy 344.17 76.2)
		)
		(stroke
			(width 0)
			(type default)
		)
	)
	(wire
		(pts
			(xy 265.43 245.11) (xy 265.43 252.73)
		)
		(stroke
			(width 0)
			(type default)
		)
	)
	(wire
		(pts
			(xy 270.51 269.24) (xy 270.51 271.78)
		)
		(stroke
			(width 0)
			(type default)
		)
	)
	(wire
		(pts
			(xy 57.15 91.44) (xy 57.15 106.68)
		)
		(stroke
			(width 0)
			(type default)
		)
	)
	(wire
		(pts
			(xy 73.66 55.88) (xy 73.66 63.5)
		)
		(stroke
			(width 0)
			(type default)
		)
	)
	(wire
		(pts
			(xy 257.81 245.11) (xy 257.81 262.89)
		)
		(stroke
			(width 0)
			(type default)
		)
	)
	(wire
		(pts
			(xy 364.49 198.12) (xy 360.68 198.12)
		)
		(stroke
			(width 0)
			(type default)
		)
	)
	(wire
		(pts
			(xy 186.69 66.04) (xy 200.66 66.04)
		)
		(stroke
			(width 0)
			(type default)
		)
	)
	(wire
		(pts
			(xy 199.39 237.49) (xy 198.12 237.49)
		)
		(stroke
			(width 0)
			(type default)
		)
	)
	(wire
		(pts
			(xy 71.12 33.02) (xy 73.66 33.02)
		)
		(stroke
			(width 0)
			(type default)
		)
	)
	(wire
		(pts
			(xy 289.56 166.37) (xy 298.45 166.37)
		)
		(stroke
			(width 0)
			(type default)
		)
	)
	(wire
		(pts
			(xy 162.56 99.06) (xy 160.02 99.06)
		)
		(stroke
			(width 0)
			(type default)
		)
	)
	(wire
		(pts
			(xy 154.94 133.35) (xy 157.48 133.35)
		)
		(stroke
			(width 0)
			(type default)
		)
	)
	(wire
		(pts
			(xy 35.56 128.27) (xy 35.56 129.54)
		)
		(stroke
			(width 0)
			(type default)
		)
	)
	(wire
		(pts
			(xy 166.37 80.01) (xy 152.4 80.01)
		)
		(stroke
			(width 0)
			(type default)
		)
	)
	(wire
		(pts
			(xy 308.61 121.92) (xy 313.69 121.92)
		)
		(stroke
			(width 0)
			(type default)
		)
	)
	(wire
		(pts
			(xy 154.94 180.34) (xy 154.94 182.88)
		)
		(stroke
			(width 0)
			(type default)
		)
	)
	(wire
		(pts
			(xy 198.12 255.27) (xy 198.12 257.81)
		)
		(stroke
			(width 0)
			(type default)
		)
	)
	(wire
		(pts
			(xy 71.12 38.1) (xy 86.36 38.1)
		)
		(stroke
			(width 0)
			(type default)
		)
	)
	(wire
		(pts
			(xy 318.77 68.58) (xy 318.77 73.66)
		)
		(stroke
			(width 0)
			(type default)
		)
	)
	(wire
		(pts
			(xy 262.89 237.49) (xy 262.89 240.03)
		)
		(stroke
			(width 0)
			(type default)
		)
	)
	(wire
		(pts
			(xy 320.04 45.72) (xy 321.31 45.72)
		)
		(stroke
			(width 0)
			(type default)
		)
	)
	(wire
		(pts
			(xy 236.22 201.93) (xy 222.25 201.93)
		)
		(stroke
			(width 0)
			(type default)
		)
	)
	(wire
		(pts
			(xy 187.96 232.41) (xy 199.39 232.41)
		)
		(stroke
			(width 0)
			(type default)
		)
	)
	(wire
		(pts
			(xy 223.52 121.92) (xy 224.79 121.92)
		)
		(stroke
			(width 0)
			(type default)
		)
	)
	(wire
		(pts
			(xy 298.45 175.26) (xy 298.45 176.53)
		)
		(stroke
			(width 0)
			(type default)
		)
	)
	(wire
		(pts
			(xy 345.44 241.3) (xy 341.63 241.3)
		)
		(stroke
			(width 0)
			(type default)
		)
	)
	(wire
		(pts
			(xy 54.61 114.3) (xy 54.61 116.84)
		)
		(stroke
			(width 0)
			(type default)
		)
	)
	(wire
		(pts
			(xy 321.31 45.72) (xy 344.17 45.72)
		)
		(stroke
			(width 0)
			(type default)
		)
	)
	(wire
		(pts
			(xy 281.94 130.81) (xy 281.94 132.08)
		)
		(stroke
			(width 0)
			(type default)
		)
	)
	(wire
		(pts
			(xy 193.04 87.63) (xy 193.04 93.98)
		)
		(stroke
			(width 0)
			(type default)
		)
	)
	(wire
		(pts
			(xy 260.35 124.46) (xy 250.19 124.46)
		)
		(stroke
			(width 0)
			(type default)
		)
	)
	(wire
		(pts
			(xy 313.69 166.37) (xy 313.69 165.1)
		)
		(stroke
			(width 0)
			(type default)
		)
	)
	(wire
		(pts
			(xy 149.86 106.68) (xy 149.86 109.22)
		)
		(stroke
			(width 0)
			(type default)
		)
	)
	(wire
		(pts
			(xy 257.81 121.92) (xy 257.81 127)
		)
		(stroke
			(width 0)
			(type default)
		)
	)
	(wire
		(pts
			(xy 242.57 116.84) (xy 242.57 118.11)
		)
		(stroke
			(width 0)
			(type default)
		)
	)
	(wire
		(pts
			(xy 222.25 234.95) (xy 232.41 234.95)
		)
		(stroke
			(width 0)
			(type default)
		)
	)
	(wire
		(pts
			(xy 156.21 27.94) (xy 156.21 29.21)
		)
		(stroke
			(width 0)
			(type default)
		)
	)
	(wire
		(pts
			(xy 257.81 171.45) (xy 260.35 171.45)
		)
		(stroke
			(width 0)
			(type default)
		)
	)
	(wire
		(pts
			(xy 267.97 237.49) (xy 270.51 237.49)
		)
		(stroke
			(width 0)
			(type default)
		)
	)
	(wire
		(pts
			(xy 152.4 82.55) (xy 166.37 82.55)
		)
		(stroke
			(width 0)
			(type default)
		)
	)
	(wire
		(pts
			(xy 275.59 127) (xy 276.86 127)
		)
		(stroke
			(width 0)
			(type default)
		)
	)
	(wire
		(pts
			(xy 147.32 133.35) (xy 149.86 133.35)
		)
		(stroke
			(width 0)
			(type default)
		)
	)
	(wire
		(pts
			(xy 328.93 50.8) (xy 344.17 50.8)
		)
		(stroke
			(width 0)
			(type default)
		)
	)
	(wire
		(pts
			(xy 232.41 228.6) (xy 232.41 234.95)
		)
		(stroke
			(width 0)
			(type default)
		)
	)
	(wire
		(pts
			(xy 199.39 201.93) (xy 177.8 201.93)
		)
		(stroke
			(width 0)
			(type default)
		)
	)
	(wire
		(pts
			(xy 199.39 260.35) (xy 198.12 260.35)
		)
		(stroke
			(width 0)
			(type default)
		)
	)
	(wire
		(pts
			(xy 222.25 232.41) (xy 229.87 232.41)
		)
		(stroke
			(width 0)
			(type default)
		)
	)
	(wire
		(pts
			(xy 298.45 170.18) (xy 298.45 166.37)
		)
		(stroke
			(width 0)
			(type default)
		)
	)
	(wire
		(pts
			(xy 330.2 116.84) (xy 344.17 116.84)
		)
		(stroke
			(width 0)
			(type default)
		)
	)
	(wire
		(pts
			(xy 222.25 237.49) (xy 234.95 237.49)
		)
		(stroke
			(width 0)
			(type default)
		)
	)
	(wire
		(pts
			(xy 260.35 237.49) (xy 262.89 237.49)
		)
		(stroke
			(width 0)
			(type default)
		)
	)
	(wire
		(pts
			(xy 308.61 166.37) (xy 313.69 166.37)
		)
		(stroke
			(width 0)
			(type default)
		)
	)
	(wire
		(pts
			(xy 177.8 78.74) (xy 177.8 82.55)
		)
		(stroke
			(width 0)
			(type default)
		)
	)
	(wire
		(pts
			(xy 147.32 26.67) (xy 147.32 27.94)
		)
		(stroke
			(width 0)
			(type default)
		)
	)
	(wire
		(pts
			(xy 44.45 114.3) (xy 44.45 111.76)
		)
		(stroke
			(width 0)
			(type default)
		)
	)
	(wire
		(pts
			(xy 57.15 76.2) (xy 57.15 91.44)
		)
		(stroke
			(width 0)
			(type default)
		)
	)
	(wire
		(pts
			(xy 223.52 63.5) (xy 247.65 63.5)
		)
		(stroke
			(width 0)
			(type default)
		)
	)
	(wire
		(pts
			(xy 260.35 271.78) (xy 257.81 271.78)
		)
		(stroke
			(width 0)
			(type default)
		)
	)
	(wire
		(pts
			(xy 281.94 168.91) (xy 281.94 170.18)
		)
		(stroke
			(width 0)
			(type default)
		)
	)
	(wire
		(pts
			(xy 44.45 128.27) (xy 44.45 129.54)
		)
		(stroke
			(width 0)
			(type default)
		)
	)
	(wire
		(pts
			(xy 257.81 161.29) (xy 257.81 166.37)
		)
		(stroke
			(width 0)
			(type default)
		)
	)
	(wire
		(pts
			(xy 289.56 166.37) (xy 289.56 170.18)
		)
		(stroke
			(width 0)
			(type default)
		)
	)
	(wire
		(pts
			(xy 273.05 271.78) (xy 273.05 274.32)
		)
		(stroke
			(width 0)
			(type default)
		)
	)
	(wire
		(pts
			(xy 270.51 271.78) (xy 273.05 271.78)
		)
		(stroke
			(width 0)
			(type default)
		)
	)
	(wire
		(pts
			(xy 358.14 154.94) (xy 358.14 156.21)
		)
		(stroke
			(width 0)
			(type default)
		)
	)
	(wire
		(pts
			(xy 200.66 96.52) (xy 190.5 96.52)
		)
		(stroke
			(width 0)
			(type default)
		)
	)
	(wire
		(pts
			(xy 162.56 99.06) (xy 162.56 101.6)
		)
		(stroke
			(width 0)
			(type default)
		)
	)
	(wire
		(pts
			(xy 73.66 91.44) (xy 73.66 106.68)
		)
		(stroke
			(width 0)
			(type default)
		)
	)
	(wire
		(pts
			(xy 257.81 127) (xy 260.35 127)
		)
		(stroke
			(width 0)
			(type default)
		)
	)
	(wire
		(pts
			(xy 172.72 180.34) (xy 172.72 182.88)
		)
		(stroke
			(width 0)
			(type default)
		)
	)
	(wire
		(pts
			(xy 43.18 71.12) (xy 59.69 71.12)
		)
		(stroke
			(width 0)
			(type default)
		)
	)
	(wire
		(pts
			(xy 157.48 119.38) (xy 157.48 125.73)
		)
		(stroke
			(width 0)
			(type default)
		)
	)
	(wire
		(pts
			(xy 152.4 99.06) (xy 152.4 101.6)
		)
		(stroke
			(width 0)
			(type default)
		)
	)
	(wire
		(pts
			(xy 328.93 68.58) (xy 344.17 68.58)
		)
		(stroke
			(width 0)
			(type default)
		)
	)
	(wire
		(pts
			(xy 373.38 129.54) (xy 373.38 132.08)
		)
		(stroke
			(width 0)
			(type default)
		)
	)
	(wire
		(pts
			(xy 229.87 218.44) (xy 229.87 226.06)
		)
		(stroke
			(width 0)
			(type default)
		)
	)
	(wire
		(pts
			(xy 154.94 130.81) (xy 154.94 133.35)
		)
		(stroke
			(width 0)
			(type default)
		)
	)
	(wire
		(pts
			(xy 328.93 190.5) (xy 328.93 187.96)
		)
		(stroke
			(width 0)
			(type default)
		)
	)
	(wire
		(pts
			(xy 157.48 130.81) (xy 157.48 133.35)
		)
		(stroke
			(width 0)
			(type default)
		)
	)
	(wire
		(pts
			(xy 345.44 166.37) (xy 336.55 166.37)
		)
		(stroke
			(width 0)
			(type default)
		)
	)
	(wire
		(pts
			(xy 367.03 166.37) (xy 358.14 166.37)
		)
		(stroke
			(width 0)
			(type default)
		)
	)
	(wire
		(pts
			(xy 375.92 193.04) (xy 360.68 193.04)
		)
		(stroke
			(width 0)
			(type default)
		)
	)
	(wire
		(pts
			(xy 242.57 212.09) (xy 242.57 210.82)
		)
		(stroke
			(width 0)
			(type default)
		)
	)
	(wire
		(pts
			(xy 200.66 93.98) (xy 193.04 93.98)
		)
		(stroke
			(width 0)
			(type default)
		)
	)
	(wire
		(pts
			(xy 35.56 114.3) (xy 44.45 114.3)
		)
		(stroke
			(width 0)
			(type default)
		)
	)
	(wire
		(pts
			(xy 189.23 165.1) (xy 189.23 180.34)
		)
		(stroke
			(width 0)
			(type default)
		)
	)
	(wire
		(pts
			(xy 173.99 104.14) (xy 173.99 105.41)
		)
		(stroke
			(width 0)
			(type default)
		)
	)
	(wire
		(pts
			(xy 265.43 237.49) (xy 267.97 237.49)
		)
		(stroke
			(width 0)
			(type default)
		)
	)
	(wire
		(pts
			(xy 179.07 72.39) (xy 177.8 72.39)
		)
		(stroke
			(width 0)
			(type default)
		)
	)
	(wire
		(pts
			(xy 152.4 111.76) (xy 200.66 111.76)
		)
		(stroke
			(width 0)
			(type default)
		)
	)
	(wire
		(pts
			(xy 373.38 132.08) (xy 369.57 132.08)
		)
		(stroke
			(width 0)
			(type default)
		)
	)
	(wire
		(pts
			(xy 193.04 87.63) (xy 189.23 87.63)
		)
		(stroke
			(width 0)
			(type default)
		)
	)
	(wire
		(pts
			(xy 59.69 124.46) (xy 57.15 124.46)
		)
		(stroke
			(width 0)
			(type default)
		)
	)
	(wire
		(pts
			(xy 273.05 234.95) (xy 273.05 237.49)
		)
		(stroke
			(width 0)
			(type default)
		)
	)
	(wire
		(pts
			(xy 59.69 45.72) (xy 57.15 45.72)
		)
		(stroke
			(width 0)
			(type default)
		)
	)
	(wire
		(pts
			(xy 275.59 121.92) (xy 289.56 121.92)
		)
		(stroke
			(width 0)
			(type default)
		)
	)
	(wire
		(pts
			(xy 344.17 227.33) (xy 344.17 224.79)
		)
		(stroke
			(width 0)
			(type default)
		)
	)
	(wire
		(pts
			(xy 256.54 220.98) (xy 270.51 220.98)
		)
		(stroke
			(width 0)
			(type default)
		)
	)
	(wire
		(pts
			(xy 245.11 217.17) (xy 245.11 220.98)
		)
		(stroke
			(width 0)
			(type default)
		)
	)
	(wire
		(pts
			(xy 336.55 158.75) (xy 336.55 156.21)
		)
		(stroke
			(width 0)
			(type default)
		)
	)
	(wire
		(pts
			(xy 147.32 133.35) (xy 147.32 135.89)
		)
		(stroke
			(width 0)
			(type default)
		)
	)
	(wire
		(pts
			(xy 182.88 43.18) (xy 194.31 43.18)
		)
		(stroke
			(width 0)
			(type default)
		)
	)
	(wire
		(pts
			(xy 160.02 133.35) (xy 162.56 133.35)
		)
		(stroke
			(width 0)
			(type default)
		)
	)
	(wire
		(pts
			(xy 250.19 116.84) (xy 242.57 116.84)
		)
		(stroke
			(width 0)
			(type default)
		)
	)
	(wire
		(pts
			(xy 242.57 116.84) (xy 242.57 115.57)
		)
		(stroke
			(width 0)
			(type default)
		)
	)
	(wire
		(pts
			(xy 149.86 109.22) (xy 200.66 109.22)
		)
		(stroke
			(width 0)
			(type default)
		)
	)
	(wire
		(pts
			(xy 162.56 124.46) (xy 162.56 125.73)
		)
		(stroke
			(width 0)
			(type default)
		)
	)
	(wire
		(pts
			(xy 180.34 78.74) (xy 180.34 80.01)
		)
		(stroke
			(width 0)
			(type default)
		)
	)
	(wire
		(pts
			(xy 257.81 237.49) (xy 260.35 237.49)
		)
		(stroke
			(width 0)
			(type default)
		)
	)
	(wire
		(pts
			(xy 73.66 48.26) (xy 71.12 48.26)
		)
		(stroke
			(width 0)
			(type default)
		)
	)
	(wire
		(pts
			(xy 289.56 130.81) (xy 289.56 132.08)
		)
		(stroke
			(width 0)
			(type default)
		)
	)
	(wire
		(pts
			(xy 152.4 133.35) (xy 154.94 133.35)
		)
		(stroke
			(width 0)
			(type default)
		)
	)
	(wire
		(pts
			(xy 232.41 228.6) (xy 233.68 228.6)
		)
		(stroke
			(width 0)
			(type default)
		)
	)
	(wire
		(pts
			(xy 162.56 130.81) (xy 162.56 133.35)
		)
		(stroke
			(width 0)
			(type default)
		)
	)
	(wire
		(pts
			(xy 275.59 166.37) (xy 289.56 166.37)
		)
		(stroke
			(width 0)
			(type default)
		)
	)
	(wire
		(pts
			(xy 165.1 43.18) (xy 173.99 43.18)
		)
		(stroke
			(width 0)
			(type default)
		)
	)
	(text "PCIe redriver"
		(exclude_from_sim no)
		(at 207.01 42.164 0)
		(effects
			(font
				(size 2 2)
				(thickness 0.8)
				(bold yes)
			)
			(justify left bottom)
		)
	)
	(text "ISET resistor value:\ntarget current limit = 0.6 A (peak OCuLink pin current)\nAP22615 datasheet, page 3, ISET pin description\nI_{LIM} (A) = 6800 / R_{LIM} (Ohms)\n0.6 A = 6800 / R_{LIM} Ohms\nR_{LIM} = 6800 / 0.6 = 11333 Ohms ~= 11.3 kOhms"
		(exclude_from_sim no)
		(at 248.666 183.388 0)
		(effects
			(font
				(size 1.27 1.27)
			)
			(justify left top)
		)
	)
	(text "OCuLink e-fuses"
		(exclude_from_sim no)
		(at 262.89 103.632 0)
		(effects
			(font
				(size 2 2)
				(thickness 0.8)
				(bold yes)
			)
			(justify left bottom)
		)
	)
	(text "FR4 loss ~= 7.9dB/m/GHz; \n31.6 dB/m @ 4GHz\nJOB avg PCIe2 TX trace length ~= 51.0 mm\nJOB connector to redriver trace length ~= 60.7 mm\nfor 111.7 mm loss = 3.53 dB\nEQ[2:0] = 2'b010 gives 3.9 dB EQ @ 4 GHz\nFG[1:0] = 2'b10 for -0.5 dB (aiming for 0dB)\nSW1 = 1 for 1200 mVp-p swing"
		(exclude_from_sim no)
		(at 98.552 129.794 0)
		(effects
			(font
				(size 1.27 1.27)
			)
			(justify left bottom)
		)
	)
	(text "FR4 loss ~= 7.9dB/m/GHz; \n31.6 dB/m @ 4GHz\nOCuLink 1m cable loss ~= 6.0 dB @ 4.5 GHz\nOCuLink connector to redriver trace length ~= 47.5 mm\nfor 47.5 mm loss = 1.5 dB\n6.0 dB + 1.5 dB = 7.5 dB\nEQ[2:0] = 6'b110 gives 7.8 dB EQ @ 4 GHz\nFG[1:0] = 2'b10 for -0.5 dB (aiming for 0dB)\nSW1 = 1 for 1200 mVp-p swing"
		(exclude_from_sim no)
		(at 98.806 248.92 0)
		(effects
			(font
				(size 1.27 1.27)
			)
			(justify left bottom)
		)
	)
	(text "ISET resistor value:\ntarget current limit = 1.2 A (2x peak OCuLink pin current)\nAP22615 datasheet, page 3, ISET pin description\nI_{LIM} (A) = 6800 / R_{LIM} (Ohms)\n1.2 A = 6800 / R_{LIM} Ohms\nR_{LIM} = 6800 / 1.2 = 5666 Ohms ~= 5.6 kOhms\nreal current limit ~= 1.214 A"
		(exclude_from_sim no)
		(at 248.412 139.446 0)
		(effects
			(font
				(size 1.27 1.27)
			)
			(justify left top)
		)
	)
	(text "JOB acts as a ROOT Device\nREFCLK utilizes A12(+)/A13(-)"
		(exclude_from_sim no)
		(at 331.724 138.684 0)
		(effects
			(font
				(size 1.27 1.27)
			)
			(justify left)
		)
	)
	(label "~{PCIE_RST}"
		(at 330.2 66.04 0)
		(fields_autoplaced yes)
		(effects
			(font
				(size 1.27 1.27)
			)
			(justify left bottom)
		)
	)
	(label "PCIE_{O}_TX1-"
		(at 273.05 63.5 180)
		(fields_autoplaced yes)
		(effects
			(font
				(size 1.27 1.27)
			)
			(justify right bottom)
		)
	)
	(label "~{PCIE_CWAKE}"
		(at 375.92 193.04 180)
		(fields_autoplaced yes)
		(effects
			(font
				(size 1.27 1.27)
			)
			(justify right bottom)
		)
	)
	(label "I2C_SCL"
		(at 152.4 82.55 0)
		(fields_autoplaced yes)
		(effects
			(font
				(size 1.27 1.27)
			)
			(justify left bottom)
		)
	)
	(label "RX_EQ1"
		(at 223.52 250.19 0)
		(fields_autoplaced yes)
		(effects
			(font
				(size 1.27 1.27)
			)
			(justify left bottom)
		)
	)
	(label "PCIE_{I}_RX0+"
		(at 86.36 45.72 180)
		(fields_autoplaced yes)
		(effects
			(font
				(size 1.27 1.27)
			)
			(justify right bottom)
		)
	)
	(label "TX_FG0"
		(at 193.04 119.38 0)
		(fields_autoplaced yes)
		(effects
			(font
				(size 1.27 1.27)
			)
			(justify left bottom)
		)
	)
	(label "~{CPRSNT}"
		(at 304.8 68.58 0)
		(fields_autoplaced yes)
		(effects
			(font
				(size 1.27 1.27)
			)
			(justify left bottom)
		)
	)
	(label "PCIE_{I}_TX0+"
		(at 186.69 73.66 0)
		(fields_autoplaced yes)
		(effects
			(font
				(size 1.27 1.27)
			)
			(justify left bottom)
		)
	)
	(label "PCIE_{O}_RX0+"
		(at 236.22 212.09 180)
		(fields_autoplaced yes)
		(effects
			(font
				(size 1.27 1.27)
			)
			(justify right bottom)
		)
	)
	(label "RX_EQ2"
		(at 223.52 252.73 0)
		(fields_autoplaced yes)
		(effects
			(font
				(size 1.27 1.27)
			)
			(justify left bottom)
		)
	)
	(label "TX_FG1"
		(at 193.04 121.92 0)
		(fields_autoplaced yes)
		(effects
			(font
				(size 1.27 1.27)
			)
			(justify left bottom)
		)
	)
	(label "PCIE_{O}_TX1-"
		(at 330.2 116.84 0)
		(fields_autoplaced yes)
		(effects
			(font
				(size 1.27 1.27)
			)
			(justify left bottom)
		)
	)
	(label "PCIE_{I}_RX0+"
		(at 149.86 212.09 0)
		(fields_autoplaced yes)
		(effects
			(font
				(size 1.27 1.27)
			)
			(justify left bottom)
		)
	)
	(label "PCIE_{O}_RX1-"
		(at 330.2 86.36 0)
		(fields_autoplaced yes)
		(effects
			(font
				(size 1.27 1.27)
			)
			(justify left bottom)
		)
	)
	(label "TX_EQ2"
		(at 193.04 114.3 0)
		(fields_autoplaced yes)
		(effects
			(font
				(size 1.27 1.27)
			)
			(justify left bottom)
		)
	)
	(label "~{CPRSNT}"
		(at 234.95 93.98 180)
		(fields_autoplaced yes)
		(effects
			(font
				(size 1.27 1.27)
			)
			(justify right bottom)
		)
	)
	(label "I2C_SDA"
		(at 48.26 109.22 0)
		(fields_autoplaced yes)
		(effects
			(font
				(size 1.27 1.27)
			)
			(justify left bottom)
		)
	)
	(label "PCIE_{I}_TX1-"
		(at 186.69 63.5 0)
		(fields_autoplaced yes)
		(effects
			(font
				(size 1.27 1.27)
			)
			(justify left bottom)
		)
	)
	(label "PCIE_{I}_RX0-"
		(at 149.86 209.55 0)
		(fields_autoplaced yes)
		(effects
			(font
				(size 1.27 1.27)
			)
			(justify left bottom)
		)
	)
	(label "RX_FG1"
		(at 223.52 260.35 0)
		(fields_autoplaced yes)
		(effects
			(font
				(size 1.27 1.27)
			)
			(justify left bottom)
		)
	)
	(label "PCIE_{O}_RX0-"
		(at 330.2 78.74 0)
		(fields_autoplaced yes)
		(effects
			(font
				(size 1.27 1.27)
			)
			(justify left bottom)
		)
	)
	(label "PCIE_{I}_TX0-"
		(at 44.45 40.64 0)
		(fields_autoplaced yes)
		(effects
			(font
				(size 1.27 1.27)
			)
			(justify left bottom)
		)
	)
	(label "PCIE_{O}_TX0+"
		(at 330.2 106.68 0)
		(fields_autoplaced yes)
		(effects
			(font
				(size 1.27 1.27)
			)
			(justify left bottom)
		)
	)
	(label "~{CPRSNT}"
		(at 375.92 195.58 180)
		(fields_autoplaced yes)
		(effects
			(font
				(size 1.27 1.27)
			)
			(justify right bottom)
		)
	)
	(label "PCIE_{I}_RX1+"
		(at 149.86 204.47 0)
		(fields_autoplaced yes)
		(effects
			(font
				(size 1.27 1.27)
			)
			(justify left bottom)
		)
	)
	(label "PCIE_{I}_C.RX1+"
		(at 182.88 204.47 0)
		(fields_autoplaced yes)
		(effects
			(font
				(size 1.27 1.27)
			)
			(justify left bottom)
		)
	)
	(label "PCIE_{O}_C.TX0+"
		(at 240.03 73.66 180)
		(fields_autoplaced yes)
		(effects
			(font
				(size 1.27 1.27)
			)
			(justify right bottom)
		)
	)
	(label "JOB_GPIO07"
		(at 316.23 195.58 0)
		(fields_autoplaced yes)
		(effects
			(font
				(size 1.27 1.27)
			)
			(justify left bottom)
		)
	)
	(label "PCIE_{O}_TX0+"
		(at 273.05 73.66 180)
		(fields_autoplaced yes)
		(effects
			(font
				(size 1.27 1.27)
			)
			(justify right bottom)
		)
	)
	(label "PCIE_{I}_RX1-"
		(at 149.86 201.93 0)
		(fields_autoplaced yes)
		(effects
			(font
				(size 1.27 1.27)
			)
			(justify left bottom)
		)
	)
	(label "PCIE_{I}_RX1+"
		(at 86.36 38.1 180)
		(fields_autoplaced yes)
		(effects
			(font
				(size 1.27 1.27)
			)
			(justify right bottom)
		)
	)
	(label "PCIE_{I}_TX0+"
		(at 44.45 43.18 0)
		(fields_autoplaced yes)
		(effects
			(font
				(size 1.27 1.27)
			)
			(justify left bottom)
		)
	)
	(label "TX_EQ1"
		(at 193.04 111.76 0)
		(fields_autoplaced yes)
		(effects
			(font
				(size 1.27 1.27)
			)
			(justify left bottom)
		)
	)
	(label "PCIE_{O}_RX1-"
		(at 236.22 201.93 180)
		(fields_autoplaced yes)
		(effects
			(font
				(size 1.27 1.27)
			)
			(justify right bottom)
		)
	)
	(label "PCIE_{O}_C.TX0-"
		(at 240.03 71.12 180)
		(fields_autoplaced yes)
		(effects
			(font
				(size 1.27 1.27)
			)
			(justify right bottom)
		)
	)
	(label "PCIE_{I}_TX1+"
		(at 44.45 35.56 0)
		(fields_autoplaced yes)
		(effects
			(font
				(size 1.27 1.27)
			)
			(justify left bottom)
		)
	)
	(label "I2C_SDA"
		(at 304.8 53.34 0)
		(fields_autoplaced yes)
		(effects
			(font
				(size 1.27 1.27)
			)
			(justify left bottom)
		)
	)
	(label "PCIE_CLK+"
		(at 330.2 58.42 0)
		(fields_autoplaced yes)
		(effects
			(font
				(size 1.27 1.27)
			)
			(justify left bottom)
		)
	)
	(label "PCIE_{I}_C.RX0+"
		(at 182.88 212.09 0)
		(fields_autoplaced yes)
		(effects
			(font
				(size 1.27 1.27)
			)
			(justify left bottom)
		)
	)
	(label "PCIE_{O}_RX1+"
		(at 330.2 83.82 0)
		(fields_autoplaced yes)
		(effects
			(font
				(size 1.27 1.27)
			)
			(justify left bottom)
		)
	)
	(label "TX_EQ0"
		(at 193.04 109.22 0)
		(fields_autoplaced yes)
		(effects
			(font
				(size 1.27 1.27)
			)
			(justify left bottom)
		)
	)
	(label "PCIE_{O}_RX0+"
		(at 330.2 76.2 0)
		(fields_autoplaced yes)
		(effects
			(font
				(size 1.27 1.27)
			)
			(justify left bottom)
		)
	)
	(label "PCIE_{O}_RX1+"
		(at 236.22 204.47 180)
		(fields_autoplaced yes)
		(effects
			(font
				(size 1.27 1.27)
			)
			(justify right bottom)
		)
	)
	(label "JOB_GPIO07"
		(at 43.18 71.12 0)
		(fields_autoplaced yes)
		(effects
			(font
				(size 1.27 1.27)
			)
			(justify left bottom)
		)
	)
	(label "I2C_SCL"
		(at 270.51 220.98 180)
		(fields_autoplaced yes)
		(effects
			(font
				(size 1.27 1.27)
			)
			(justify right bottom)
		)
	)
	(label "JOB_GPIO09"
		(at 316.23 193.04 0)
		(fields_autoplaced yes)
		(effects
			(font
				(size 1.27 1.27)
			)
			(justify left bottom)
		)
	)
	(label "PCIE_{O}_TX0-"
		(at 330.2 109.22 0)
		(fields_autoplaced yes)
		(effects
			(font
				(size 1.27 1.27)
			)
			(justify left bottom)
		)
	)
	(label "RX_EQ0"
		(at 223.52 247.65 0)
		(fields_autoplaced yes)
		(effects
			(font
				(size 1.27 1.27)
			)
			(justify left bottom)
		)
	)
	(label "I2C_SDA"
		(at 152.4 80.01 0)
		(fields_autoplaced yes)
		(effects
			(font
				(size 1.27 1.27)
			)
			(justify left bottom)
		)
	)
	(label "PCIE_{I}_TX0-"
		(at 186.69 71.12 0)
		(fields_autoplaced yes)
		(effects
			(font
				(size 1.27 1.27)
			)
			(justify left bottom)
		)
	)
	(label "PCIE_{I}_RX1-"
		(at 86.36 35.56 180)
		(fields_autoplaced yes)
		(effects
			(font
				(size 1.27 1.27)
			)
			(justify right bottom)
		)
	)
	(label "PCIE_CLK+"
		(at 45.72 50.8 0)
		(fields_autoplaced yes)
		(effects
			(font
				(size 1.27 1.27)
			)
			(justify left bottom)
		)
	)
	(label "I2C_SDA"
		(at 270.51 218.44 180)
		(fields_autoplaced yes)
		(effects
			(font
				(size 1.27 1.27)
			)
			(justify right bottom)
		)
	)
	(label "PCIE_{O}_C.TX1-"
		(at 240.03 63.5 180)
		(fields_autoplaced yes)
		(effects
			(font
				(size 1.27 1.27)
			)
			(justify right bottom)
		)
	)
	(label "~{PCIE_RST}"
		(at 43.18 63.5 0)
		(fields_autoplaced yes)
		(effects
			(font
				(size 1.27 1.27)
			)
			(justify left bottom)
		)
	)
	(label "~{CPRSNT}"
		(at 187.96 232.41 0)
		(fields_autoplaced yes)
		(effects
			(font
				(size 1.27 1.27)
			)
			(justify left bottom)
		)
	)
	(label "I2C_SCL"
		(at 304.8 50.8 0)
		(fields_autoplaced yes)
		(effects
			(font
				(size 1.27 1.27)
			)
			(justify left bottom)
		)
	)
	(label "RX_SW"
		(at 223.52 262.89 0)
		(fields_autoplaced yes)
		(effects
			(font
				(size 1.27 1.27)
			)
			(justify left bottom)
		)
	)
	(label "PCIE_{I}_RX0-"
		(at 86.36 43.18 180)
		(fields_autoplaced yes)
		(effects
			(font
				(size 1.27 1.27)
			)
			(justify right bottom)
		)
	)
	(label "PCIE_{O}_TX1+"
		(at 273.05 66.04 180)
		(fields_autoplaced yes)
		(effects
			(font
				(size 1.27 1.27)
			)
			(justify right bottom)
		)
	)
	(label "PCIE_{O}_RX0-"
		(at 236.22 209.55 180)
		(fields_autoplaced yes)
		(effects
			(font
				(size 1.27 1.27)
			)
			(justify right bottom)
		)
	)
	(label "PCIE_{O}_TX1+"
		(at 330.2 114.3 0)
		(fields_autoplaced yes)
		(effects
			(font
				(size 1.27 1.27)
			)
			(justify left bottom)
		)
	)
	(label "TX_SW"
		(at 193.04 124.46 0)
		(fields_autoplaced yes)
		(effects
			(font
				(size 1.27 1.27)
			)
			(justify left bottom)
		)
	)
	(label "~{PCIE_CWAKE}"
		(at 304.8 71.12 0)
		(fields_autoplaced yes)
		(effects
			(font
				(size 1.27 1.27)
			)
			(justify left bottom)
		)
	)
	(label "PCIE_{I}_TX1-"
		(at 44.45 33.02 0)
		(fields_autoplaced yes)
		(effects
			(font
				(size 1.27 1.27)
			)
			(justify left bottom)
		)
	)
	(label "I2C_SCL"
		(at 48.26 111.76 0)
		(fields_autoplaced yes)
		(effects
			(font
				(size 1.27 1.27)
			)
			(justify left bottom)
		)
	)
	(label "PCIE_{O}_C.TX1+"
		(at 240.03 66.04 180)
		(fields_autoplaced yes)
		(effects
			(font
				(size 1.27 1.27)
			)
			(justify right bottom)
		)
	)
	(label "PCIE_{O}_TX0-"
		(at 273.05 71.12 180)
		(fields_autoplaced yes)
		(effects
			(font
				(size 1.27 1.27)
			)
			(justify right bottom)
		)
	)
	(label "RX_FG0"
		(at 223.52 257.81 0)
		(fields_autoplaced yes)
		(effects
			(font
				(size 1.27 1.27)
			)
			(justify left bottom)
		)
	)
	(label "JOB_GPIO09"
		(at 43.18 73.66 0)
		(fields_autoplaced yes)
		(effects
			(font
				(size 1.27 1.27)
			)
			(justify left bottom)
		)
	)
	(label "PCIE_CLK-"
		(at 330.2 60.96 0)
		(fields_autoplaced yes)
		(effects
			(font
				(size 1.27 1.27)
			)
			(justify left bottom)
		)
	)
	(label "PCIE_{I}_C.RX0-"
		(at 182.88 209.55 0)
		(fields_autoplaced yes)
		(effects
			(font
				(size 1.27 1.27)
			)
			(justify left bottom)
		)
	)
	(label "PCIE_{I}_C.RX1-"
		(at 182.88 201.93 0)
		(fields_autoplaced yes)
		(effects
			(font
				(size 1.27 1.27)
			)
			(justify left bottom)
		)
	)
	(label "PCIE_CLK-"
		(at 45.72 48.26 0)
		(fields_autoplaced yes)
		(effects
			(font
				(size 1.27 1.27)
			)
			(justify left bottom)
		)
	)
	(label "PCIE_{I}_TX1+"
		(at 186.69 66.04 0)
		(fields_autoplaced yes)
		(effects
			(font
				(size 1.27 1.27)
			)
			(justify left bottom)
		)
	)
	(symbol
		(lib_id "antmicropower:GND")
		(at 273.05 274.32 0)
		(mirror y)
		(unit 1)
		(exclude_from_sim no)
		(in_bom yes)
		(on_board yes)
		(dnp no)
		(property "Reference" "#PWR029"
			(at 264.16 276.86 0)
			(effects
				(font
					(size 1.27 1.27)
					(thickness 0.15)
				)
				(justify left bottom)
				(hide yes)
			)
		)
		(property "Value" "GND"
			(at 273.05 278.13 0)
			(effects
				(font
					(size 1.27 1.27)
					(thickness 0.15)
				)
			)
		)
		(property "Footprint" ""
			(at 264.16 281.94 0)
			(effects
				(font
					(size 1.27 1.27)
					(thickness 0.15)
				)
				(justify left bottom)
				(hide yes)
			)
		)
		(property "Datasheet" ""
			(at 264.16 287.02 0)
			(effects
				(font
					(size 1.27 1.27)
					(thickness 0.15)
				)
				(justify left bottom)
				(hide yes)
			)
		)
		(property "Description" ""
			(at 273.05 274.32 0)
			(effects
				(font
					(size 1.27 1.27)
				)
				(hide yes)
			)
		)
		(property "Author" "Antmicro"
			(at 264.16 281.94 0)
			(effects
				(font
					(size 1.27 1.27)
					(thickness 0.15)
				)
				(justify left bottom)
				(hide yes)
			)
		)
		(property "License" "Apache-2.0"
			(at 264.16 284.48 0)
			(effects
				(font
					(size 1.27 1.27)
					(thickness 0.15)
				)
				(justify left bottom)
				(hide yes)
			)
		)
		(pin "1"
		)
		(instances
			(project "jetson-orin-baseboard-oculink-expansion"
				(path ""
					(reference "#PWR029")
					(unit 1)
				)
			)
		)
	)
	(symbol
		(lib_id "antmicropower:GND")
		(at 172.72 187.96 0)
		(mirror y)
		(unit 1)
		(exclude_from_sim no)
		(in_bom yes)
		(on_board yes)
		(dnp no)
		(property "Reference" "#PWR027"
			(at 163.83 190.5 0)
			(effects
				(font
					(size 1.27 1.27)
					(thickness 0.15)
				)
				(justify left bottom)
				(hide yes)
			)
		)
		(property "Value" "GND"
			(at 172.72 191.77 0)
			(effects
				(font
					(size 1.27 1.27)
					(thickness 0.15)
				)
			)
		)
		(property "Footprint" ""
			(at 163.83 195.58 0)
			(effects
				(font
					(size 1.27 1.27)
					(thickness 0.15)
				)
				(justify left bottom)
				(hide yes)
			)
		)
		(property "Datasheet" ""
			(at 163.83 200.66 0)
			(effects
				(font
					(size 1.27 1.27)
					(thickness 0.15)
				)
				(justify left bottom)
				(hide yes)
			)
		)
		(property "Description" ""
			(at 172.72 187.96 0)
			(effects
				(font
					(size 1.27 1.27)
				)
				(hide yes)
			)
		)
		(property "Author" "Antmicro"
			(at 163.83 195.58 0)
			(effects
				(font
					(size 1.27 1.27)
					(thickness 0.15)
				)
				(justify left bottom)
				(hide yes)
			)
		)
		(property "License" "Apache-2.0"
			(at 163.83 198.12 0)
			(effects
				(font
					(size 1.27 1.27)
					(thickness 0.15)
				)
				(justify left bottom)
				(hide yes)
			)
		)
		(pin "1"
		)
		(instances
			(project "jetson-orin-baseboard-oculink-expansion"
				(path ""
					(reference "#PWR027")
					(unit 1)
				)
			)
		)
	)
	(symbol
		(lib_id "antmicroResistors0402:R_1k_0402")
		(at 154.94 101.6 270)
		(unit 1)
		(exclude_from_sim no)
		(in_bom yes)
		(on_board yes)
		(dnp yes)
		(property "Reference" "R23"
			(at 154.94 97.79 0)
			(effects
				(font
					(size 1.27 1.27)
					(thickness 0.15)
				)
				(justify right)
			)
		)
		(property "Value" "R_1k_0402"
			(at 142.24 121.92 0)
			(effects
				(font
					(size 1.27 1.27)
					(thickness 0.15)
				)
				(justify left bottom)
				(hide yes)
			)
		)
		(property "Footprint" "antmicro-footprints:R_0402_1005Metric"
			(at 139.7 121.92 0)
			(effects
				(font
					(size 1.27 1.27)
					(thickness 0.15)
				)
				(justify left bottom)
				(hide yes)
			)
		)
		(property "Datasheet" "https://www.bourns.com/docs/product-datasheets/cr.pdf"
			(at 137.16 121.92 0)
			(effects
				(font
					(size 1.27 1.27)
					(thickness 0.15)
				)
				(justify left bottom)
				(hide yes)
			)
		)
		(property "Description" "SMD Chip Resistor, 1 kohm, ± 1%, 63 mW, 0402 [1005 Metric], Thick Film, General Purpose"
			(at 154.94 101.6 0)
			(effects
				(font
					(size 1.27 1.27)
				)
				(hide yes)
			)
		)
		(property "MPN" "CR0402-FX-1001GLF"
			(at 134.62 121.92 0)
			(effects
				(font
					(size 1.27 1.27)
					(thickness 0.15)
				)
				(justify left bottom)
				(hide yes)
			)
		)
		(property "Manufacturer" "Bourns"
			(at 132.08 121.92 0)
			(effects
				(font
					(size 1.27 1.27)
					(thickness 0.15)
				)
				(justify left bottom)
				(hide yes)
			)
		)
		(property "License" "Apache-2.0"
			(at 129.54 121.92 0)
			(effects
				(font
					(size 1.27 1.27)
					(thickness 0.15)
				)
				(justify left bottom)
				(hide yes)
			)
		)
		(property "Author" "Antmicro"
			(at 127 121.92 0)
			(effects
				(font
					(size 1.27 1.27)
					(thickness 0.15)
				)
				(justify left bottom)
				(hide yes)
			)
		)
		(property "Val" "1k"
			(at 156.21 101.6 0)
			(effects
				(font
					(size 1.27 1.27)
					(thickness 0.15)
				)
				(justify right)
			)
		)
		(property "Tolerance" "1%"
			(at 144.78 121.92 0)
			(effects
				(font
					(size 1.27 1.27)
				)
				(justify left bottom)
				(hide yes)
			)
		)
		(property "Public" "False"
			(at 124.46 121.92 0)
			(effects
				(font
					(size 1.27 1.27)
				)
				(justify left bottom)
				(hide yes)
			)
		)
		(pin "1"
		)
		(pin "2"
		)
		(instances
			(project "jetson-orin-baseboard-oculink-expansion"
				(path ""
					(reference "R23")
					(unit 1)
				)
			)
		)
	)
	(symbol
		(lib_id "antmicroResistors0402:R_10k_0402")
		(at 250.19 118.11 270)
		(unit 1)
		(exclude_from_sim no)
		(in_bom yes)
		(on_board yes)
		(dnp no)
		(property "Reference" "R43"
			(at 251.46 119.38 90)
			(effects
				(font
					(size 1.27 1.27)
					(thickness 0.15)
				)
				(justify left)
			)
		)
		(property "Value" "R_10k_0402"
			(at 237.49 138.43 0)
			(effects
				(font
					(size 1.27 1.27)
					(thickness 0.15)
				)
				(justify left bottom)
				(hide yes)
			)
		)
		(property "Footprint" "antmicro-footprints:R_0402_1005Metric"
			(at 234.95 138.43 0)
			(effects
				(font
					(size 1.27 1.27)
					(thickness 0.15)
				)
				(justify left bottom)
				(hide yes)
			)
		)
		(property "Datasheet" "https://www.bourns.com/docs/product-datasheets/cr.pdf"
			(at 232.41 138.43 0)
			(effects
				(font
					(size 1.27 1.27)
					(thickness 0.15)
				)
				(justify left bottom)
				(hide yes)
			)
		)
		(property "Description" "SMD Chip Resistor, 10 kohm, ± 1%, 62.5 mW, 0402 [1005 Metric], Thick Film, General Purpose"
			(at 250.19 118.11 0)
			(effects
				(font
					(size 1.27 1.27)
				)
				(hide yes)
			)
		)
		(property "MPN" "CR0402-FX-1002GLF"
			(at 229.87 138.43 0)
			(effects
				(font
					(size 1.27 1.27)
					(thickness 0.15)
				)
				(justify left bottom)
				(hide yes)
			)
		)
		(property "Manufacturer" "Bourns"
			(at 227.33 138.43 0)
			(effects
				(font
					(size 1.27 1.27)
					(thickness 0.15)
				)
				(justify left bottom)
				(hide yes)
			)
		)
		(property "License" "Apache-2.0"
			(at 224.79 138.43 0)
			(effects
				(font
					(size 1.27 1.27)
					(thickness 0.15)
				)
				(justify left bottom)
				(hide yes)
			)
		)
		(property "Author" "Antmicro"
			(at 222.25 138.43 0)
			(effects
				(font
					(size 1.27 1.27)
					(thickness 0.15)
				)
				(justify left bottom)
				(hide yes)
			)
		)
		(property "Val" "10k"
			(at 251.46 121.92 90)
			(effects
				(font
					(size 1.27 1.27)
					(thickness 0.15)
				)
				(justify left)
			)
		)
		(property "Tolerance" "1%"
			(at 240.03 138.43 0)
			(effects
				(font
					(size 1.27 1.27)
				)
				(justify left bottom)
				(hide yes)
			)
		)
		(pin "1"
		)
		(pin "2"
		)
		(instances
			(project ""
				(path ""
					(reference "R43")
					(unit 1)
				)
			)
		)
	)
	(symbol
		(lib_id "antmicroResistors0402:R_10k_0402")
		(at 180.34 78.74 90)
		(unit 1)
		(exclude_from_sim no)
		(in_bom yes)
		(on_board yes)
		(dnp no)
		(property "Reference" "R42"
			(at 182.88 74.168 0)
			(effects
				(font
					(size 1.27 1.27)
					(thickness 0.15)
				)
				(justify right)
			)
		)
		(property "Value" "R_10k_0402"
			(at 193.04 58.42 0)
			(effects
				(font
					(size 1.27 1.27)
					(thickness 0.15)
				)
				(justify left bottom)
				(hide yes)
			)
		)
		(property "Footprint" "antmicro-footprints:R_0402_1005Metric"
			(at 195.58 58.42 0)
			(effects
				(font
					(size 1.27 1.27)
					(thickness 0.15)
				)
				(justify left bottom)
				(hide yes)
			)
		)
		(property "Datasheet" "https://www.bourns.com/docs/product-datasheets/cr.pdf"
			(at 198.12 58.42 0)
			(effects
				(font
					(size 1.27 1.27)
					(thickness 0.15)
				)
				(justify left bottom)
				(hide yes)
			)
		)
		(property "Description" "SMD Chip Resistor, 10 kohm, ± 1%, 62.5 mW, 0402 [1005 Metric], Thick Film, General Purpose"
			(at 180.34 78.74 0)
			(effects
				(font
					(size 1.27 1.27)
				)
				(hide yes)
			)
		)
		(property "MPN" "CR0402-FX-1002GLF"
			(at 200.66 58.42 0)
			(effects
				(font
					(size 1.27 1.27)
					(thickness 0.15)
				)
				(justify left bottom)
				(hide yes)
			)
		)
		(property "Manufacturer" "Bourns"
			(at 203.2 58.42 0)
			(effects
				(font
					(size 1.27 1.27)
					(thickness 0.15)
				)
				(justify left bottom)
				(hide yes)
			)
		)
		(property "License" "Apache-2.0"
			(at 205.74 58.42 0)
			(effects
				(font
					(size 1.27 1.27)
					(thickness 0.15)
				)
				(justify left bottom)
				(hide yes)
			)
		)
		(property "Author" "Antmicro"
			(at 208.28 58.42 0)
			(effects
				(font
					(size 1.27 1.27)
					(thickness 0.15)
				)
				(justify left bottom)
				(hide yes)
			)
		)
		(property "Val" "10k"
			(at 184.658 74.422 0)
			(effects
				(font
					(size 1.27 1.27)
					(thickness 0.15)
				)
				(justify right)
			)
		)
		(property "Tolerance" "1%"
			(at 190.5 58.42 0)
			(effects
				(font
					(size 1.27 1.27)
				)
				(justify left bottom)
				(hide yes)
			)
		)
		(pin "2"
		)
		(pin "1"
		)
		(instances
			(project "jetson-orin-baseboard-oculink-expansion"
				(path ""
					(reference "R42")
					(unit 1)
				)
			)
		)
	)
	(symbol
		(lib_id "antmicroResistors0402:R_10k_0402")
		(at 177.8 78.74 90)
		(unit 1)
		(exclude_from_sim no)
		(in_bom yes)
		(on_board yes)
		(dnp no)
		(property "Reference" "R40"
			(at 173.482 74.168 0)
			(effects
				(font
					(size 1.27 1.27)
					(thickness 0.15)
				)
				(justify right)
			)
		)
		(property "Value" "R_10k_0402"
			(at 190.5 58.42 0)
			(effects
				(font
					(size 1.27 1.27)
					(thickness 0.15)
				)
				(justify left bottom)
				(hide yes)
			)
		)
		(property "Footprint" "antmicro-footprints:R_0402_1005Metric"
			(at 193.04 58.42 0)
			(effects
				(font
					(size 1.27 1.27)
					(thickness 0.15)
				)
				(justify left bottom)
				(hide yes)
			)
		)
		(property "Datasheet" "https://www.bourns.com/docs/product-datasheets/cr.pdf"
			(at 195.58 58.42 0)
			(effects
				(font
					(size 1.27 1.27)
					(thickness 0.15)
				)
				(justify left bottom)
				(hide yes)
			)
		)
		(property "Description" "SMD Chip Resistor, 10 kohm, ± 1%, 62.5 mW, 0402 [1005 Metric], Thick Film, General Purpose"
			(at 177.8 78.74 0)
			(effects
				(font
					(size 1.27 1.27)
				)
				(hide yes)
			)
		)
		(property "MPN" "CR0402-FX-1002GLF"
			(at 198.12 58.42 0)
			(effects
				(font
					(size 1.27 1.27)
					(thickness 0.15)
				)
				(justify left bottom)
				(hide yes)
			)
		)
		(property "Manufacturer" "Bourns"
			(at 200.66 58.42 0)
			(effects
				(font
					(size 1.27 1.27)
					(thickness 0.15)
				)
				(justify left bottom)
				(hide yes)
			)
		)
		(property "License" "Apache-2.0"
			(at 203.2 58.42 0)
			(effects
				(font
					(size 1.27 1.27)
					(thickness 0.15)
				)
				(justify left bottom)
				(hide yes)
			)
		)
		(property "Author" "Antmicro"
			(at 205.74 58.42 0)
			(effects
				(font
					(size 1.27 1.27)
					(thickness 0.15)
				)
				(justify left bottom)
				(hide yes)
			)
		)
		(property "Val" "10k"
			(at 175.26 74.422 0)
			(effects
				(font
					(size 1.27 1.27)
					(thickness 0.15)
				)
				(justify right)
			)
		)
		(property "Tolerance" "1%"
			(at 187.96 58.42 0)
			(effects
				(font
					(size 1.27 1.27)
				)
				(justify left bottom)
				(hide yes)
			)
		)
		(pin "2"
		)
		(pin "1"
		)
		(instances
			(project "jetson-orin-baseboard-oculink-expansion"
				(path ""
					(reference "R40")
					(unit 1)
				)
			)
		)
	)
	(symbol
		(lib_id "antmicroResistors0402:R_1k_0402")
		(at 152.4 101.6 270)
		(unit 1)
		(exclude_from_sim no)
		(in_bom yes)
		(on_board yes)
		(dnp no)
		(property "Reference" "R21"
			(at 152.4 97.79 0)
			(effects
				(font
					(size 1.27 1.27)
					(thickness 0.15)
				)
				(justify right)
			)
		)
		(property "Value" "R_1k_0402"
			(at 139.7 121.92 0)
			(effects
				(font
					(size 1.27 1.27)
					(thickness 0.15)
				)
				(justify left bottom)
				(hide yes)
			)
		)
		(property "Footprint" "antmicro-footprints:R_0402_1005Metric"
			(at 137.16 121.92 0)
			(effects
				(font
					(size 1.27 1.27)
					(thickness 0.15)
				)
				(justify left bottom)
				(hide yes)
			)
		)
		(property "Datasheet" "https://www.bourns.com/docs/product-datasheets/cr.pdf"
			(at 134.62 121.92 0)
			(effects
				(font
					(size 1.27 1.27)
					(thickness 0.15)
				)
				(justify left bottom)
				(hide yes)
			)
		)
		(property "Description" "SMD Chip Resistor, 1 kohm, ± 1%, 63 mW, 0402 [1005 Metric], Thick Film, General Purpose"
			(at 152.4 101.6 0)
			(effects
				(font
					(size 1.27 1.27)
				)
				(hide yes)
			)
		)
		(property "MPN" "CR0402-FX-1001GLF"
			(at 132.08 121.92 0)
			(effects
				(font
					(size 1.27 1.27)
					(thickness 0.15)
				)
				(justify left bottom)
				(hide yes)
			)
		)
		(property "Manufacturer" "Bourns"
			(at 129.54 121.92 0)
			(effects
				(font
					(size 1.27 1.27)
					(thickness 0.15)
				)
				(justify left bottom)
				(hide yes)
			)
		)
		(property "License" "Apache-2.0"
			(at 127 121.92 0)
			(effects
				(font
					(size 1.27 1.27)
					(thickness 0.15)
				)
				(justify left bottom)
				(hide yes)
			)
		)
		(property "Author" "Antmicro"
			(at 124.46 121.92 0)
			(effects
				(font
					(size 1.27 1.27)
					(thickness 0.15)
				)
				(justify left bottom)
				(hide yes)
			)
		)
		(property "Val" "1k"
			(at 153.67 101.6 0)
			(effects
				(font
					(size 1.27 1.27)
					(thickness 0.15)
				)
				(justify right)
			)
		)
		(property "Tolerance" "1%"
			(at 142.24 121.92 0)
			(effects
				(font
					(size 1.27 1.27)
				)
				(justify left bottom)
				(hide yes)
			)
		)
		(property "Public" "False"
			(at 121.92 121.92 0)
			(effects
				(font
					(size 1.27 1.27)
				)
				(justify left bottom)
				(hide yes)
			)
		)
		(pin "1"
		)
		(pin "2"
		)
		(instances
			(project "jetson-orin-baseboard-oculink-expansion"
				(path ""
					(reference "R21")
					(unit 1)
				)
			)
		)
	)
	(symbol
		(lib_id "antmicropower:GND")
		(at 281.94 132.08 0)
		(mirror y)
		(unit 1)
		(exclude_from_sim no)
		(in_bom yes)
		(on_board yes)
		(dnp no)
		(property "Reference" "#PWR06"
			(at 273.05 134.62 0)
			(effects
				(font
					(size 1.27 1.27)
					(thickness 0.15)
				)
				(justify left bottom)
				(hide yes)
			)
		)
		(property "Value" "GND"
			(at 281.94 135.89 0)
			(effects
				(font
					(size 1.27 1.27)
					(thickness 0.15)
				)
			)
		)
		(property "Footprint" ""
			(at 273.05 139.7 0)
			(effects
				(font
					(size 1.27 1.27)
					(thickness 0.15)
				)
				(justify left bottom)
				(hide yes)
			)
		)
		(property "Datasheet" ""
			(at 273.05 144.78 0)
			(effects
				(font
					(size 1.27 1.27)
					(thickness 0.15)
				)
				(justify left bottom)
				(hide yes)
			)
		)
		(property "Description" ""
			(at 281.94 132.08 0)
			(effects
				(font
					(size 1.27 1.27)
				)
				(hide yes)
			)
		)
		(property "Author" "Antmicro"
			(at 273.05 139.7 0)
			(effects
				(font
					(size 1.27 1.27)
					(thickness 0.15)
				)
				(justify left bottom)
				(hide yes)
			)
		)
		(property "License" "Apache-2.0"
			(at 273.05 142.24 0)
			(effects
				(font
					(size 1.27 1.27)
					(thickness 0.15)
				)
				(justify left bottom)
				(hide yes)
			)
		)
		(pin "1"
		)
		(instances
			(project "jetson-orin-baseboard-oculink-expansion"
				(path ""
					(reference "#PWR06")
					(unit 1)
				)
			)
		)
	)
	(symbol
		(lib_id "antmicropower:GND")
		(at 396.24 203.2 0)
		(unit 1)
		(exclude_from_sim no)
		(in_bom yes)
		(on_board yes)
		(dnp no)
		(fields_autoplaced yes)
		(property "Reference" "#PWR019"
			(at 396.24 209.55 0)
			(effects
				(font
					(size 1.27 1.27)
				)
				(justify left bottom)
				(hide yes)
			)
		)
		(property "Value" "GND"
			(at 396.24 207.01 0)
			(effects
				(font
					(size 1.27 1.27)
					(thickness 0.15)
				)
			)
		)
		(property "Footprint" ""
			(at 405.13 210.82 0)
			(effects
				(font
					(size 1.27 1.27)
					(thickness 0.15)
				)
				(justify left bottom)
				(hide yes)
			)
		)
		(property "Datasheet" ""
			(at 405.13 215.9 0)
			(effects
				(font
					(size 1.27 1.27)
					(thickness 0.15)
				)
				(justify left bottom)
				(hide yes)
			)
		)
		(property "Description" ""
			(at 396.24 203.2 0)
			(effects
				(font
					(size 1.27 1.27)
				)
				(hide yes)
			)
		)
		(property "Author" "Antmicro"
			(at 405.13 210.82 0)
			(effects
				(font
					(size 1.27 1.27)
					(thickness 0.15)
				)
				(justify left bottom)
				(hide yes)
			)
		)
		(property "License" "Apache-2.0"
			(at 405.13 213.36 0)
			(effects
				(font
					(size 1.27 1.27)
					(thickness 0.15)
				)
				(justify left bottom)
				(hide yes)
			)
		)
		(pin "1"
		)
		(instances
			(project "jetson-orin-baseboard-oculink-expansion"
				(path ""
					(reference "#PWR019")
					(unit 1)
				)
			)
		)
	)
	(symbol
		(lib_id "antmicroCapacitors0402:C_220n_0402")
		(at 247.65 63.5 0)
		(unit 1)
		(exclude_from_sim no)
		(in_bom yes)
		(on_board yes)
		(dnp no)
		(property "Reference" "C35"
			(at 246.38 62.23 0)
			(effects
				(font
					(size 1.27 1.27)
					(thickness 0.15)
				)
			)
		)
		(property "Value" "C_220n_0402"
			(at 267.97 73.66 0)
			(effects
				(font
					(size 1.27 1.27)
					(thickness 0.15)
				)
				(justify left bottom)
				(hide yes)
			)
		)
		(property "Footprint" "antmicro-footprints:C_0402_1005Metric"
			(at 267.97 76.2 0)
			(effects
				(font
					(size 1.27 1.27)
					(thickness 0.15)
				)
				(justify left bottom)
				(hide yes)
			)
		)
		(property "Datasheet" "https://www.yageo.com/en/Chart/Download/pdf/CC0402KRX5R6BB224"
			(at 267.97 78.74 0)
			(effects
				(font
					(size 1.27 1.27)
					(thickness 0.15)
				)
				(justify left bottom)
				(hide yes)
			)
		)
		(property "Description" "SMD Multilayer Ceramic Capacitor, 0.22 µF, 10 V, 0402 [1005 Metric], ± 10%, X5R, CC Series"
			(at 247.65 63.5 0)
			(effects
				(font
					(size 1.27 1.27)
				)
				(hide yes)
			)
		)
		(property "MPN" "CC0402KRX5R6BB224"
			(at 267.97 81.28 0)
			(effects
				(font
					(size 1.27 1.27)
					(thickness 0.15)
				)
				(justify left bottom)
				(hide yes)
			)
		)
		(property "Manufacturer" "YAGEO"
			(at 267.97 83.82 0)
			(effects
				(font
					(size 1.27 1.27)
					(thickness 0.15)
				)
				(justify left bottom)
				(hide yes)
			)
		)
		(property "License" "Apache-2.0"
			(at 267.97 86.36 0)
			(effects
				(font
					(size 1.27 1.27)
					(thickness 0.15)
				)
				(justify left bottom)
				(hide yes)
			)
		)
		(property "Author" "Antmicro"
			(at 267.97 88.9 0)
			(effects
				(font
					(size 1.27 1.27)
					(thickness 0.15)
				)
				(justify left bottom)
				(hide yes)
			)
		)
		(property "Val" "220n"
			(at 254 62.23 0)
			(effects
				(font
					(size 1.27 1.27)
					(thickness 0.15)
				)
			)
		)
		(property "Voltage" ""
			(at 267.97 91.44 0)
			(effects
				(font
					(size 1.27 1.27)
				)
				(justify left bottom)
				(hide yes)
			)
		)
		(property "Dielectric" ""
			(at 267.97 93.98 0)
			(effects
				(font
					(size 1.27 1.27)
				)
				(justify left bottom)
				(hide yes)
			)
		)
		(property "Public" "False"
			(at 267.97 96.52 0)
			(effects
				(font
					(size 1.27 1.27)
				)
				(justify left bottom)
				(hide yes)
			)
		)
		(pin "1"
		)
		(pin "2"
		)
		(instances
			(project "jetson-orin-baseboard-oculink-expansion"
				(path ""
					(reference "C35")
					(unit 1)
				)
			)
		)
	)
	(symbol
		(lib_id "antmicroTestPoints:TP_0.75mm_SMD")
		(at 233.68 226.06 0)
		(mirror x)
		(unit 1)
		(exclude_from_sim no)
		(in_bom no)
		(on_board yes)
		(dnp no)
		(property "Reference" "TP17"
			(at 240.03 226.06 0)
			(effects
				(font
					(size 1.27 1.27)
					(thickness 0.15)
				)
			)
		)
		(property "Value" "TP_0.75mm_SMD"
			(at 244.475 222.25 0)
			(effects
				(font
					(size 1.27 1.27)
					(thickness 0.15)
				)
				(justify left bottom)
				(hide yes)
			)
		)
		(property "Footprint" "antmicro-footprints:TP_SMD_0.75mm"
			(at 244.475 219.71 0)
			(effects
				(font
					(size 1.27 1.27)
					(thickness 0.15)
				)
				(justify left bottom)
				(hide yes)
			)
		)
		(property "Datasheet" ""
			(at 251.46 213.36 0)
			(effects
				(font
					(size 1.27 1.27)
					(thickness 0.15)
				)
				(justify left bottom)
				(hide yes)
			)
		)
		(property "Description" "SMT test point"
			(at 233.68 226.06 0)
			(effects
				(font
					(size 1.27 1.27)
				)
				(hide yes)
			)
		)
		(property "MPN" ""
			(at 244.475 214.63 0)
			(effects
				(font
					(size 1.27 1.27)
					(thickness 0.15)
				)
				(justify left bottom)
				(hide yes)
			)
		)
		(property "Manufacturer" ""
			(at 244.475 219.71 0)
			(effects
				(font
					(size 1.27 1.27)
					(thickness 0.15)
				)
				(justify left bottom)
				(hide yes)
			)
		)
		(property "Author" "Antmicro"
			(at 244.475 217.17 0)
			(effects
				(font
					(size 1.27 1.27)
					(thickness 0.15)
				)
				(justify left bottom)
				(hide yes)
			)
		)
		(property "License" "Apache-2.0"
			(at 244.475 214.63 0)
			(effects
				(font
					(size 1.27 1.27)
					(thickness 0.15)
				)
				(justify left bottom)
				(hide yes)
			)
		)
		(property "Public" "False"
			(at 243.84 212.09 0)
			(effects
				(font
					(size 1.27 1.27)
				)
				(justify left bottom)
				(hide yes)
			)
		)
		(pin "1"
		)
		(instances
			(project "jetson-orin-baseboard-oculink-expansion"
				(path ""
					(reference "TP17")
					(unit 1)
				)
			)
		)
	)
	(symbol
		(lib_id "antmicroCapacitors0402:C_100n_0402")
		(at 396.24 196.85 90)
		(unit 1)
		(exclude_from_sim no)
		(in_bom yes)
		(on_board yes)
		(dnp no)
		(fields_autoplaced yes)
		(property "Reference" "C6"
			(at 398.78 193.0336 90)
			(effects
				(font
					(size 1.27 1.27)
					(thickness 0.15)
				)
				(justify right)
			)
		)
		(property "Value" "C_100n_0402"
			(at 406.4 176.53 0)
			(effects
				(font
					(size 1.27 1.27)
					(thickness 0.15)
				)
				(justify left bottom)
				(hide yes)
			)
		)
		(property "Footprint" "antmicro-footprints:C_0402_1005Metric"
			(at 408.94 176.53 0)
			(effects
				(font
					(size 1.27 1.27)
					(thickness 0.15)
				)
				(justify left bottom)
				(hide yes)
			)
		)
		(property "Datasheet" "https://www.murata.com/products/productdetail?partno=GRM155R61H104KE14%23"
			(at 411.48 176.53 0)
			(effects
				(font
					(size 1.27 1.27)
					(thickness 0.15)
				)
				(justify left bottom)
				(hide yes)
			)
		)
		(property "Description" "SMD Multilayer Ceramic Capacitor, 0.1 µF, 50 V, 0402 [1005 Metric], ± 10%, X5R, GRM Series"
			(at 396.24 196.85 0)
			(effects
				(font
					(size 1.27 1.27)
				)
				(hide yes)
			)
		)
		(property "MPN" "GRM155R61H104KE14D"
			(at 414.02 176.53 0)
			(effects
				(font
					(size 1.27 1.27)
					(thickness 0.15)
				)
				(justify left bottom)
				(hide yes)
			)
		)
		(property "Manufacturer" "Murata"
			(at 416.56 176.53 0)
			(effects
				(font
					(size 1.27 1.27)
					(thickness 0.15)
				)
				(justify left bottom)
				(hide yes)
			)
		)
		(property "License" "Apache-2.0"
			(at 419.1 176.53 0)
			(effects
				(font
					(size 1.27 1.27)
					(thickness 0.15)
				)
				(justify left bottom)
				(hide yes)
			)
		)
		(property "Author" "Antmicro"
			(at 421.64 176.53 0)
			(effects
				(font
					(size 1.27 1.27)
					(thickness 0.15)
				)
				(justify left bottom)
				(hide yes)
			)
		)
		(property "Val" "100n"
			(at 398.78 195.5736 90)
			(effects
				(font
					(size 1.27 1.27)
					(thickness 0.15)
				)
				(justify right)
			)
		)
		(property "Voltage" "50V"
			(at 424.18 176.53 0)
			(effects
				(font
					(size 1.27 1.27)
				)
				(justify left bottom)
				(hide yes)
			)
		)
		(property "Dielectric" "X5R"
			(at 426.72 176.53 0)
			(effects
				(font
					(size 1.27 1.27)
				)
				(justify left bottom)
				(hide yes)
			)
		)
		(pin "1"
		)
		(pin "2"
		)
		(instances
			(project "jetson-orin-baseboard-oculink-expansion"
				(path ""
					(reference "C6")
					(unit 1)
				)
			)
		)
	)
	(symbol
		(lib_id "antmicroTestPoints:TP_1.5mm_SMD")
		(at 43.18 63.5 180)
		(unit 1)
		(exclude_from_sim no)
		(in_bom no)
		(on_board yes)
		(dnp no)
		(property "Reference" "TP7"
			(at 35.56 63.754 0)
			(effects
				(font
					(size 1.27 1.27)
					(thickness 0.15)
				)
				(justify right)
			)
		)
		(property "Value" "TP_1.5mm_SMD"
			(at 27.94 55.88 0)
			(effects
				(font
					(size 1.27 1.27)
					(thickness 0.15)
				)
				(justify left bottom)
				(hide yes)
			)
		)
		(property "Footprint" "antmicro-footprints:TP_SMD_1.5mm"
			(at 27.94 53.34 0)
			(effects
				(font
					(size 1.27 1.27)
					(thickness 0.15)
				)
				(justify left bottom)
				(hide yes)
			)
		)
		(property "Datasheet" ""
			(at 25.4 50.8 0)
			(effects
				(font
					(size 1.27 1.27)
					(thickness 0.15)
				)
				(justify left bottom)
				(hide yes)
			)
		)
		(property "Description" "test point, SMT"
			(at 43.18 63.5 0)
			(effects
				(font
					(size 1.27 1.27)
				)
				(hide yes)
			)
		)
		(property "MPN" ""
			(at 43.18 63.5 0)
			(effects
				(font
					(size 1.27 1.27)
				)
				(hide yes)
			)
		)
		(property "Manufacturer" ""
			(at 43.18 63.5 0)
			(effects
				(font
					(size 1.27 1.27)
				)
				(hide yes)
			)
		)
		(property "Author" "Antmicro"
			(at 27.94 48.26 0)
			(effects
				(font
					(size 1.27 1.27)
					(thickness 0.15)
				)
				(justify left bottom)
				(hide yes)
			)
		)
		(property "License" "Apache-2.0"
			(at 27.94 45.72 0)
			(effects
				(font
					(size 1.27 1.27)
					(thickness 0.15)
				)
				(justify left bottom)
				(hide yes)
			)
		)
		(pin "1"
		)
		(instances
			(project "jetson-orin-baseboard-oculink-expansion"
				(path ""
					(reference "TP7")
					(unit 1)
				)
			)
		)
	)
	(symbol
		(lib_id "antmicroResistors0402:R_0R_0402")
		(at 323.85 50.8 0)
		(unit 1)
		(exclude_from_sim no)
		(in_bom yes)
		(on_board yes)
		(dnp no)
		(property "Reference" "R20"
			(at 322.072 49.784 0)
			(effects
				(font
					(size 1.27 1.27)
					(thickness 0.15)
				)
			)
		)
		(property "Value" "R_0R_0402"
			(at 344.17 63.5 0)
			(effects
				(font
					(size 1.27 1.27)
					(thickness 0.15)
				)
				(justify left bottom)
				(hide yes)
			)
		)
		(property "Footprint" "antmicro-footprints:R_0402_1005Metric"
			(at 344.17 66.04 0)
			(effects
				(font
					(size 1.27 1.27)
					(thickness 0.15)
				)
				(justify left bottom)
				(hide yes)
			)
		)
		(property "Datasheet" "https://industrial.panasonic.com/cdbs/www-data/pdf/RDA0000/AOA0000C301.pdf"
			(at 344.17 68.58 0)
			(effects
				(font
					(size 1.27 1.27)
					(thickness 0.15)
				)
				(justify left bottom)
				(hide yes)
			)
		)
		(property "Description" "SMD Chip Resistor, Jumper, 0 ohm, 100 mW, 0402 [1005 Metric], Thick Film, General Purpose"
			(at 323.85 50.8 0)
			(effects
				(font
					(size 1.27 1.27)
				)
				(hide yes)
			)
		)
		(property "MPN" "ERJ2GE0R00X"
			(at 344.17 71.12 0)
			(effects
				(font
					(size 1.27 1.27)
					(thickness 0.15)
				)
				(justify left bottom)
				(hide yes)
			)
		)
		(property "Manufacturer" "Panasonic"
			(at 344.17 73.66 0)
			(effects
				(font
					(size 1.27 1.27)
					(thickness 0.15)
				)
				(justify left bottom)
				(hide yes)
			)
		)
		(property "License" "Apache-2.0"
			(at 344.17 76.2 0)
			(effects
				(font
					(size 1.27 1.27)
					(thickness 0.15)
				)
				(justify left bottom)
				(hide yes)
			)
		)
		(property "Author" "Antmicro"
			(at 344.17 78.74 0)
			(effects
				(font
					(size 1.27 1.27)
					(thickness 0.15)
				)
				(justify left bottom)
				(hide yes)
			)
		)
		(property "Val" "0R"
			(at 330.2 49.784 0)
			(effects
				(font
					(size 1.27 1.27)
					(thickness 0.15)
				)
			)
		)
		(property "Tolerance" "~"
			(at 344.17 60.96 0)
			(effects
				(font
					(size 1.27 1.27)
				)
				(justify left bottom)
				(hide yes)
			)
		)
		(property "Current" "1A"
			(at 344.17 81.28 0)
			(effects
				(font
					(size 1.27 1.27)
					(thickness 0.15)
				)
				(justify left bottom)
				(hide yes)
			)
		)
		(pin "1"
		)
		(pin "2"
		)
		(instances
			(project "jetson-orin-baseboard-oculink-expansion"
				(path ""
					(reference "R20")
					(unit 1)
				)
			)
		)
	)
	(symbol
		(lib_id "antmicroResistors0402:R_1k_0402")
		(at 260.35 269.24 270)
		(mirror x)
		(unit 1)
		(exclude_from_sim no)
		(in_bom yes)
		(on_board yes)
		(dnp yes)
		(property "Reference" "R13"
			(at 260.35 273.05 0)
			(effects
				(font
					(size 1.27 1.27)
					(thickness 0.15)
				)
				(justify right)
			)
		)
		(property "Value" "R_1k_0402"
			(at 247.65 248.92 0)
			(effects
				(font
					(size 1.27 1.27)
					(thickness 0.15)
				)
				(justify left bottom)
				(hide yes)
			)
		)
		(property "Footprint" "antmicro-footprints:R_0402_1005Metric"
			(at 245.11 248.92 0)
			(effects
				(font
					(size 1.27 1.27)
					(thickness 0.15)
				)
				(justify left bottom)
				(hide yes)
			)
		)
		(property "Datasheet" "https://www.bourns.com/docs/product-datasheets/cr.pdf"
			(at 242.57 248.92 0)
			(effects
				(font
					(size 1.27 1.27)
					(thickness 0.15)
				)
				(justify left bottom)
				(hide yes)
			)
		)
		(property "Description" "SMD Chip Resistor, 1 kohm, ± 1%, 63 mW, 0402 [1005 Metric], Thick Film, General Purpose"
			(at 260.35 269.24 0)
			(effects
				(font
					(size 1.27 1.27)
				)
				(hide yes)
			)
		)
		(property "MPN" "CR0402-FX-1001GLF"
			(at 240.03 248.92 0)
			(effects
				(font
					(size 1.27 1.27)
					(thickness 0.15)
				)
				(justify left bottom)
				(hide yes)
			)
		)
		(property "Manufacturer" "Bourns"
			(at 237.49 248.92 0)
			(effects
				(font
					(size 1.27 1.27)
					(thickness 0.15)
				)
				(justify left bottom)
				(hide yes)
			)
		)
		(property "License" "Apache-2.0"
			(at 234.95 248.92 0)
			(effects
				(font
					(size 1.27 1.27)
					(thickness 0.15)
				)
				(justify left bottom)
				(hide yes)
			)
		)
		(property "Author" "Antmicro"
			(at 232.41 248.92 0)
			(effects
				(font
					(size 1.27 1.27)
					(thickness 0.15)
				)
				(justify left bottom)
				(hide yes)
			)
		)
		(property "Val" "1k"
			(at 261.62 269.24 0)
			(effects
				(font
					(size 1.27 1.27)
					(thickness 0.15)
				)
				(justify right)
			)
		)
		(property "Tolerance" "1%"
			(at 250.19 248.92 0)
			(effects
				(font
					(size 1.27 1.27)
				)
				(justify left bottom)
				(hide yes)
			)
		)
		(property "Public" "False"
			(at 229.87 248.92 0)
			(effects
				(font
					(size 1.27 1.27)
				)
				(justify left bottom)
				(hide yes)
			)
		)
		(pin "1"
		)
		(pin "2"
		)
		(instances
			(project "jetson-orin-baseboard-oculink-expansion"
				(path ""
					(reference "R13")
					(unit 1)
				)
			)
		)
	)
	(symbol
		(lib_id "antmicroCapacitors0402:C_100n_0402")
		(at 289.56 130.81 90)
		(unit 1)
		(exclude_from_sim no)
		(in_bom yes)
		(on_board yes)
		(dnp no)
		(property "Reference" "C31"
			(at 291.338 127 90)
			(effects
				(font
					(size 1.27 1.27)
					(thickness 0.15)
				)
				(justify right)
			)
		)
		(property "Value" "C_100n_0402"
			(at 299.72 110.49 0)
			(effects
				(font
					(size 1.27 1.27)
					(thickness 0.15)
				)
				(justify left bottom)
				(hide yes)
			)
		)
		(property "Footprint" "antmicro-footprints:C_0402_1005Metric"
			(at 302.26 110.49 0)
			(effects
				(font
					(size 1.27 1.27)
					(thickness 0.15)
				)
				(justify left bottom)
				(hide yes)
			)
		)
		(property "Datasheet" "https://www.murata.com/products/productdetail?partno=GRM155R61H104KE14%23"
			(at 304.8 110.49 0)
			(effects
				(font
					(size 1.27 1.27)
					(thickness 0.15)
				)
				(justify left bottom)
				(hide yes)
			)
		)
		(property "Description" "SMD Multilayer Ceramic Capacitor, 0.1 µF, 50 V, 0402 [1005 Metric], ± 10%, X5R, GRM Series"
			(at 289.56 130.81 0)
			(effects
				(font
					(size 1.27 1.27)
				)
				(hide yes)
			)
		)
		(property "MPN" "GRM155R61H104KE14D"
			(at 307.34 110.49 0)
			(effects
				(font
					(size 1.27 1.27)
					(thickness 0.15)
				)
				(justify left bottom)
				(hide yes)
			)
		)
		(property "Manufacturer" "Murata"
			(at 309.88 110.49 0)
			(effects
				(font
					(size 1.27 1.27)
					(thickness 0.15)
				)
				(justify left bottom)
				(hide yes)
			)
		)
		(property "License" "Apache-2.0"
			(at 312.42 110.49 0)
			(effects
				(font
					(size 1.27 1.27)
					(thickness 0.15)
				)
				(justify left bottom)
				(hide yes)
			)
		)
		(property "Author" "Antmicro"
			(at 314.96 110.49 0)
			(effects
				(font
					(size 1.27 1.27)
					(thickness 0.15)
				)
				(justify left bottom)
				(hide yes)
			)
		)
		(property "Val" "100n"
			(at 291.338 129.54 90)
			(effects
				(font
					(size 1.27 1.27)
					(thickness 0.15)
				)
				(justify right)
			)
		)
		(property "Voltage" "50V"
			(at 317.5 110.49 0)
			(effects
				(font
					(size 1.27 1.27)
				)
				(justify left bottom)
				(hide yes)
			)
		)
		(property "Dielectric" "X5R"
			(at 320.04 110.49 0)
			(effects
				(font
					(size 1.27 1.27)
				)
				(justify left bottom)
				(hide yes)
			)
		)
		(pin "1"
		)
		(pin "2"
		)
		(instances
			(project "jetson-orin-baseboard-oculink-expansion"
				(path ""
					(reference "C31")
					(unit 1)
				)
			)
		)
	)
	(symbol
		(lib_id "antmicropower:PWR_FLAG")
		(at 320.04 45.72 90)
		(unit 1)
		(exclude_from_sim no)
		(in_bom yes)
		(on_board yes)
		(dnp no)
		(property "Reference" "#FLG05"
			(at 318.135 45.72 0)
			(effects
				(font
					(size 1.27 1.27)
				)
				(hide yes)
			)
		)
		(property "Value" "PWR_FLAG"
			(at 316.23 45.7199 90)
			(effects
				(font
					(size 1.27 1.27)
				)
				(justify left)
			)
		)
		(property "Footprint" ""
			(at 320.04 45.72 0)
			(effects
				(font
					(size 1.27 1.27)
				)
				(hide yes)
			)
		)
		(property "Datasheet" ""
			(at 320.04 45.72 0)
			(effects
				(font
					(size 1.27 1.27)
				)
				(hide yes)
			)
		)
		(property "Description" ""
			(at 320.04 45.72 0)
			(effects
				(font
					(size 1.27 1.27)
				)
				(hide yes)
			)
		)
		(pin "1"
		)
		(instances
			(project ""
				(path ""
					(reference "#FLG05")
					(unit 1)
				)
			)
		)
	)
	(symbol
		(lib_id "antmicroCapacitors0402:C_100n_0402")
		(at 172.72 187.96 270)
		(mirror x)
		(unit 1)
		(exclude_from_sim no)
		(in_bom yes)
		(on_board yes)
		(dnp no)
		(fields_autoplaced yes)
		(property "Reference" "C10"
			(at 170.18 184.1436 90)
			(effects
				(font
					(size 1.27 1.27)
					(thickness 0.15)
				)
				(justify right)
			)
		)
		(property "Value" "C_100n_0402"
			(at 162.56 167.64 0)
			(effects
				(font
					(size 1.27 1.27)
					(thickness 0.15)
				)
				(justify left bottom)
				(hide yes)
			)
		)
		(property "Footprint" "antmicro-footprints:C_0402_1005Metric"
			(at 160.02 167.64 0)
			(effects
				(font
					(size 1.27 1.27)
					(thickness 0.15)
				)
				(justify left bottom)
				(hide yes)
			)
		)
		(property "Datasheet" "https://www.murata.com/products/productdetail?partno=GRM155R61H104KE14%23"
			(at 157.48 167.64 0)
			(effects
				(font
					(size 1.27 1.27)
					(thickness 0.15)
				)
				(justify left bottom)
				(hide yes)
			)
		)
		(property "Description" "SMD Multilayer Ceramic Capacitor, 0.1 µF, 50 V, 0402 [1005 Metric], ± 10%, X5R, GRM Series"
			(at 172.72 187.96 0)
			(effects
				(font
					(size 1.27 1.27)
				)
				(hide yes)
			)
		)
		(property "MPN" "GRM155R61H104KE14D"
			(at 154.94 167.64 0)
			(effects
				(font
					(size 1.27 1.27)
					(thickness 0.15)
				)
				(justify left bottom)
				(hide yes)
			)
		)
		(property "Manufacturer" "Murata"
			(at 152.4 167.64 0)
			(effects
				(font
					(size 1.27 1.27)
					(thickness 0.15)
				)
				(justify left bottom)
				(hide yes)
			)
		)
		(property "License" "Apache-2.0"
			(at 149.86 167.64 0)
			(effects
				(font
					(size 1.27 1.27)
					(thickness 0.15)
				)
				(justify left bottom)
				(hide yes)
			)
		)
		(property "Author" "Antmicro"
			(at 147.32 167.64 0)
			(effects
				(font
					(size 1.27 1.27)
					(thickness 0.15)
				)
				(justify left bottom)
				(hide yes)
			)
		)
		(property "Val" "100n"
			(at 170.18 186.6836 90)
			(effects
				(font
					(size 1.27 1.27)
					(thickness 0.15)
				)
				(justify right)
			)
		)
		(property "Voltage" "50V"
			(at 144.78 167.64 0)
			(effects
				(font
					(size 1.27 1.27)
				)
				(justify left bottom)
				(hide yes)
			)
		)
		(property "Dielectric" "X5R"
			(at 142.24 167.64 0)
			(effects
				(font
					(size 1.27 1.27)
				)
				(justify left bottom)
				(hide yes)
			)
		)
		(property "Public" "False"
			(at 139.7 167.64 0)
			(effects
				(font
					(size 1.27 1.27)
				)
				(justify left bottom)
				(hide yes)
			)
		)
		(pin "1"
		)
		(pin "2"
		)
		(instances
			(project "jetson-orin-baseboard-oculink-expansion"
				(path ""
					(reference "C10")
					(unit 1)
				)
			)
		)
	)
	(symbol
		(lib_id "antmicropower:GND")
		(at 181.61 172.72 0)
		(mirror y)
		(unit 1)
		(exclude_from_sim no)
		(in_bom yes)
		(on_board yes)
		(dnp no)
		(property "Reference" "#PWR024"
			(at 172.72 175.26 0)
			(effects
				(font
					(size 1.27 1.27)
					(thickness 0.15)
				)
				(justify left bottom)
				(hide yes)
			)
		)
		(property "Value" "GND"
			(at 181.61 176.53 0)
			(effects
				(font
					(size 1.27 1.27)
					(thickness 0.15)
				)
			)
		)
		(property "Footprint" ""
			(at 172.72 180.34 0)
			(effects
				(font
					(size 1.27 1.27)
					(thickness 0.15)
				)
				(justify left bottom)
				(hide yes)
			)
		)
		(property "Datasheet" ""
			(at 172.72 185.42 0)
			(effects
				(font
					(size 1.27 1.27)
					(thickness 0.15)
				)
				(justify left bottom)
				(hide yes)
			)
		)
		(property "Description" ""
			(at 181.61 172.72 0)
			(effects
				(font
					(size 1.27 1.27)
				)
				(hide yes)
			)
		)
		(property "Author" "Antmicro"
			(at 172.72 180.34 0)
			(effects
				(font
					(size 1.27 1.27)
					(thickness 0.15)
				)
				(justify left bottom)
				(hide yes)
			)
		)
		(property "License" "Apache-2.0"
			(at 172.72 182.88 0)
			(effects
				(font
					(size 1.27 1.27)
					(thickness 0.15)
				)
				(justify left bottom)
				(hide yes)
			)
		)
		(pin "1"
		)
		(instances
			(project "jetson-orin-baseboard-oculink-expansion"
				(path ""
					(reference "#PWR024")
					(unit 1)
				)
			)
		)
	)
	(symbol
		(lib_id "antmicropower:GND")
		(at 154.94 187.96 0)
		(mirror y)
		(unit 1)
		(exclude_from_sim no)
		(in_bom yes)
		(on_board yes)
		(dnp no)
		(property "Reference" "#PWR036"
			(at 146.05 190.5 0)
			(effects
				(font
					(size 1.27 1.27)
					(thickness 0.15)
				)
				(justify left bottom)
				(hide yes)
			)
		)
		(property "Value" "GND"
			(at 154.94 191.77 0)
			(effects
				(font
					(size 1.27 1.27)
					(thickness 0.15)
				)
			)
		)
		(property "Footprint" ""
			(at 146.05 195.58 0)
			(effects
				(font
					(size 1.27 1.27)
					(thickness 0.15)
				)
				(justify left bottom)
				(hide yes)
			)
		)
		(property "Datasheet" ""
			(at 146.05 200.66 0)
			(effects
				(font
					(size 1.27 1.27)
					(thickness 0.15)
				)
				(justify left bottom)
				(hide yes)
			)
		)
		(property "Description" ""
			(at 154.94 187.96 0)
			(effects
				(font
					(size 1.27 1.27)
				)
				(hide yes)
			)
		)
		(property "Author" "Antmicro"
			(at 146.05 195.58 0)
			(effects
				(font
					(size 1.27 1.27)
					(thickness 0.15)
				)
				(justify left bottom)
				(hide yes)
			)
		)
		(property "License" "Apache-2.0"
			(at 146.05 198.12 0)
			(effects
				(font
					(size 1.27 1.27)
					(thickness 0.15)
				)
				(justify left bottom)
				(hide yes)
			)
		)
		(pin "1"
		)
		(instances
			(project "jetson-orin-baseboard-oculink-expansion"
				(path ""
					(reference "#PWR036")
					(unit 1)
				)
			)
		)
	)
	(symbol
		(lib_id "antmicropower:GND")
		(at 328.93 210.82 0)
		(unit 1)
		(exclude_from_sim no)
		(in_bom yes)
		(on_board yes)
		(dnp no)
		(fields_autoplaced yes)
		(property "Reference" "#PWR011"
			(at 328.93 217.17 0)
			(effects
				(font
					(size 1.27 1.27)
				)
				(justify left bottom)
				(hide yes)
			)
		)
		(property "Value" "GND"
			(at 328.93 214.63 0)
			(effects
				(font
					(size 1.27 1.27)
					(thickness 0.15)
				)
			)
		)
		(property "Footprint" ""
			(at 337.82 218.44 0)
			(effects
				(font
					(size 1.27 1.27)
					(thickness 0.15)
				)
				(justify left bottom)
				(hide yes)
			)
		)
		(property "Datasheet" ""
			(at 337.82 223.52 0)
			(effects
				(font
					(size 1.27 1.27)
					(thickness 0.15)
				)
				(justify left bottom)
				(hide yes)
			)
		)
		(property "Description" ""
			(at 328.93 210.82 0)
			(effects
				(font
					(size 1.27 1.27)
				)
				(hide yes)
			)
		)
		(property "Author" "Antmicro"
			(at 337.82 218.44 0)
			(effects
				(font
					(size 1.27 1.27)
					(thickness 0.15)
				)
				(justify left bottom)
				(hide yes)
			)
		)
		(property "License" "Apache-2.0"
			(at 337.82 220.98 0)
			(effects
				(font
					(size 1.27 1.27)
					(thickness 0.15)
				)
				(justify left bottom)
				(hide yes)
			)
		)
		(pin "1"
		)
		(instances
			(project "jetson-orin-baseboard-oculink-expansion"
				(path ""
					(reference "#PWR011")
					(unit 1)
				)
			)
		)
	)
	(symbol
		(lib_id "antmicropower:+3.3V")
		(at 396.24 187.96 0)
		(unit 1)
		(exclude_from_sim no)
		(in_bom yes)
		(on_board yes)
		(dnp no)
		(fields_autoplaced yes)
		(property "Reference" "#PWR016"
			(at 396.24 191.77 0)
			(effects
				(font
					(size 1.27 1.27)
				)
				(hide yes)
			)
		)
		(property "Value" "+3V3"
			(at 396.24 182.88 0)
			(effects
				(font
					(size 1.27 1.27)
				)
			)
		)
		(property "Footprint" ""
			(at 396.24 187.96 0)
			(effects
				(font
					(size 1.27 1.27)
				)
				(hide yes)
			)
		)
		(property "Datasheet" ""
			(at 396.24 187.96 0)
			(effects
				(font
					(size 1.27 1.27)
				)
				(hide yes)
			)
		)
		(property "Description" ""
			(at 396.24 187.96 0)
			(effects
				(font
					(size 1.27 1.27)
				)
				(hide yes)
			)
		)
		(pin "1"
		)
		(instances
			(project "jetson-orin-baseboard-oculink-expansion"
				(path ""
					(reference "#PWR016")
					(unit 1)
				)
			)
		)
	)
	(symbol
		(lib_id "antmicroResistors0402:R_1k_0402")
		(at 318.77 73.66 270)
		(unit 1)
		(exclude_from_sim no)
		(in_bom yes)
		(on_board yes)
		(dnp no)
		(property "Reference" "R33"
			(at 321.056 78.232 0)
			(effects
				(font
					(size 1.27 1.27)
					(thickness 0.15)
				)
				(justify right)
			)
		)
		(property "Value" "R_1k_0402"
			(at 306.07 93.98 0)
			(effects
				(font
					(size 1.27 1.27)
					(thickness 0.15)
				)
				(justify left bottom)
				(hide yes)
			)
		)
		(property "Footprint" "antmicro-footprints:R_0402_1005Metric"
			(at 303.53 93.98 0)
			(effects
				(font
					(size 1.27 1.27)
					(thickness 0.15)
				)
				(justify left bottom)
				(hide yes)
			)
		)
		(property "Datasheet" "https://www.bourns.com/docs/product-datasheets/cr.pdf"
			(at 300.99 93.98 0)
			(effects
				(font
					(size 1.27 1.27)
					(thickness 0.15)
				)
				(justify left bottom)
				(hide yes)
			)
		)
		(property "Description" "SMD Chip Resistor, 1 kohm, ± 1%, 63 mW, 0402 [1005 Metric], Thick Film, General Purpose"
			(at 318.77 73.66 0)
			(effects
				(font
					(size 1.27 1.27)
				)
				(hide yes)
			)
		)
		(property "MPN" "CR0402-FX-1001GLF"
			(at 298.45 93.98 0)
			(effects
				(font
					(size 1.27 1.27)
					(thickness 0.15)
				)
				(justify left bottom)
				(hide yes)
			)
		)
		(property "Manufacturer" "Bourns"
			(at 295.91 93.98 0)
			(effects
				(font
					(size 1.27 1.27)
					(thickness 0.15)
				)
				(justify left bottom)
				(hide yes)
			)
		)
		(property "License" "Apache-2.0"
			(at 293.37 93.98 0)
			(effects
				(font
					(size 1.27 1.27)
					(thickness 0.15)
				)
				(justify left bottom)
				(hide yes)
			)
		)
		(property "Author" "Antmicro"
			(at 290.83 93.98 0)
			(effects
				(font
					(size 1.27 1.27)
					(thickness 0.15)
				)
				(justify left bottom)
				(hide yes)
			)
		)
		(property "Val" "1k"
			(at 322.834 77.978 0)
			(effects
				(font
					(size 1.27 1.27)
					(thickness 0.15)
				)
				(justify right)
			)
		)
		(property "Tolerance" "1%"
			(at 308.61 93.98 0)
			(effects
				(font
					(size 1.27 1.27)
				)
				(justify left bottom)
				(hide yes)
			)
		)
		(property "Public" "False"
			(at 288.29 93.98 0)
			(effects
				(font
					(size 1.27 1.27)
				)
				(justify left bottom)
				(hide yes)
			)
		)
		(pin "1"
		)
		(pin "2"
		)
		(instances
			(project "jetson-orin-baseboard-oculink-expansion"
				(path ""
					(reference "R33")
					(unit 1)
				)
			)
		)
	)
	(symbol
		(lib_id "antmicropower:GND")
		(at 242.57 168.91 0)
		(unit 1)
		(exclude_from_sim no)
		(in_bom yes)
		(on_board yes)
		(dnp no)
		(property "Reference" "#PWR064"
			(at 251.46 171.45 0)
			(effects
				(font
					(size 1.27 1.27)
					(thickness 0.15)
				)
				(justify left bottom)
				(hide yes)
			)
		)
		(property "Value" "GND"
			(at 242.57 172.72 0)
			(effects
				(font
					(size 1.27 1.27)
					(thickness 0.15)
				)
			)
		)
		(property "Footprint" ""
			(at 251.46 176.53 0)
			(effects
				(font
					(size 1.27 1.27)
					(thickness 0.15)
				)
				(justify left bottom)
				(hide yes)
			)
		)
		(property "Datasheet" ""
			(at 251.46 181.61 0)
			(effects
				(font
					(size 1.27 1.27)
					(thickness 0.15)
				)
				(justify left bottom)
				(hide yes)
			)
		)
		(property "Description" ""
			(at 242.57 168.91 0)
			(effects
				(font
					(size 1.27 1.27)
				)
				(hide yes)
			)
		)
		(property "Author" "Antmicro"
			(at 251.46 176.53 0)
			(effects
				(font
					(size 1.27 1.27)
					(thickness 0.15)
				)
				(justify left bottom)
				(hide yes)
			)
		)
		(property "License" "Apache-2.0"
			(at 251.46 179.07 0)
			(effects
				(font
					(size 1.27 1.27)
					(thickness 0.15)
				)
				(justify left bottom)
				(hide yes)
			)
		)
		(pin "1"
		)
		(instances
			(project "jetson-orin-baseboard-oculink-expansion"
				(path ""
					(reference "#PWR064")
					(unit 1)
				)
			)
		)
	)
	(symbol
		(lib_id "antmicroCapacitors0402:C_100n_0402")
		(at 182.88 34.29 90)
		(unit 1)
		(exclude_from_sim no)
		(in_bom yes)
		(on_board yes)
		(dnp no)
		(fields_autoplaced yes)
		(property "Reference" "C29"
			(at 185.42 30.4736 90)
			(effects
				(font
					(size 1.27 1.27)
					(thickness 0.15)
				)
				(justify right)
			)
		)
		(property "Value" "C_100n_0402"
			(at 193.04 13.97 0)
			(effects
				(font
					(size 1.27 1.27)
					(thickness 0.15)
				)
				(justify left bottom)
				(hide yes)
			)
		)
		(property "Footprint" "antmicro-footprints:C_0402_1005Metric"
			(at 195.58 13.97 0)
			(effects
				(font
					(size 1.27 1.27)
					(thickness 0.15)
				)
				(justify left bottom)
				(hide yes)
			)
		)
		(property "Datasheet" "https://www.murata.com/products/productdetail?partno=GRM155R61H104KE14%23"
			(at 198.12 13.97 0)
			(effects
				(font
					(size 1.27 1.27)
					(thickness 0.15)
				)
				(justify left bottom)
				(hide yes)
			)
		)
		(property "Description" "SMD Multilayer Ceramic Capacitor, 0.1 µF, 50 V, 0402 [1005 Metric], ± 10%, X5R, GRM Series"
			(at 182.88 34.29 0)
			(effects
				(font
					(size 1.27 1.27)
				)
				(hide yes)
			)
		)
		(property "MPN" "GRM155R61H104KE14D"
			(at 200.66 13.97 0)
			(effects
				(font
					(size 1.27 1.27)
					(thickness 0.15)
				)
				(justify left bottom)
				(hide yes)
			)
		)
		(property "Manufacturer" "Murata"
			(at 203.2 13.97 0)
			(effects
				(font
					(size 1.27 1.27)
					(thickness 0.15)
				)
				(justify left bottom)
				(hide yes)
			)
		)
		(property "License" "Apache-2.0"
			(at 205.74 13.97 0)
			(effects
				(font
					(size 1.27 1.27)
					(thickness 0.15)
				)
				(justify left bottom)
				(hide yes)
			)
		)
		(property "Author" "Antmicro"
			(at 208.28 13.97 0)
			(effects
				(font
					(size 1.27 1.27)
					(thickness 0.15)
				)
				(justify left bottom)
				(hide yes)
			)
		)
		(property "Val" "100n"
			(at 185.42 33.0136 90)
			(effects
				(font
					(size 1.27 1.27)
					(thickness 0.15)
				)
				(justify right)
			)
		)
		(property "Voltage" "50V"
			(at 210.82 13.97 0)
			(effects
				(font
					(size 1.27 1.27)
				)
				(justify left bottom)
				(hide yes)
			)
		)
		(property "Dielectric" "X5R"
			(at 213.36 13.97 0)
			(effects
				(font
					(size 1.27 1.27)
				)
				(justify left bottom)
				(hide yes)
			)
		)
		(property "Public" "False"
			(at 215.9 13.97 0)
			(effects
				(font
					(size 1.27 1.27)
				)
				(justify left bottom)
				(hide yes)
			)
		)
		(pin "1"
		)
		(pin "2"
		)
		(instances
			(project "jetson-orin-baseboard-oculink-expansion"
				(path ""
					(reference "C29")
					(unit 1)
				)
			)
		)
	)
	(symbol
		(lib_id "antmicroCapacitors0402:C_100n_0402")
		(at 147.32 49.53 90)
		(unit 1)
		(exclude_from_sim no)
		(in_bom yes)
		(on_board yes)
		(dnp no)
		(fields_autoplaced yes)
		(property "Reference" "C18"
			(at 149.86 45.7136 90)
			(effects
				(font
					(size 1.27 1.27)
					(thickness 0.15)
				)
				(justify right)
			)
		)
		(property "Value" "C_100n_0402"
			(at 157.48 29.21 0)
			(effects
				(font
					(size 1.27 1.27)
					(thickness 0.15)
				)
				(justify left bottom)
				(hide yes)
			)
		)
		(property "Footprint" "antmicro-footprints:C_0402_1005Metric"
			(at 160.02 29.21 0)
			(effects
				(font
					(size 1.27 1.27)
					(thickness 0.15)
				)
				(justify left bottom)
				(hide yes)
			)
		)
		(property "Datasheet" "https://www.murata.com/products/productdetail?partno=GRM155R61H104KE14%23"
			(at 162.56 29.21 0)
			(effects
				(font
					(size 1.27 1.27)
					(thickness 0.15)
				)
				(justify left bottom)
				(hide yes)
			)
		)
		(property "Description" "SMD Multilayer Ceramic Capacitor, 0.1 µF, 50 V, 0402 [1005 Metric], ± 10%, X5R, GRM Series"
			(at 147.32 49.53 0)
			(effects
				(font
					(size 1.27 1.27)
				)
				(hide yes)
			)
		)
		(property "MPN" "GRM155R61H104KE14D"
			(at 165.1 29.21 0)
			(effects
				(font
					(size 1.27 1.27)
					(thickness 0.15)
				)
				(justify left bottom)
				(hide yes)
			)
		)
		(property "Manufacturer" "Murata"
			(at 167.64 29.21 0)
			(effects
				(font
					(size 1.27 1.27)
					(thickness 0.15)
				)
				(justify left bottom)
				(hide yes)
			)
		)
		(property "License" "Apache-2.0"
			(at 170.18 29.21 0)
			(effects
				(font
					(size 1.27 1.27)
					(thickness 0.15)
				)
				(justify left bottom)
				(hide yes)
			)
		)
		(property "Author" "Antmicro"
			(at 172.72 29.21 0)
			(effects
				(font
					(size 1.27 1.27)
					(thickness 0.15)
				)
				(justify left bottom)
				(hide yes)
			)
		)
		(property "Val" "100n"
			(at 149.86 48.2536 90)
			(effects
				(font
					(size 1.27 1.27)
					(thickness 0.15)
				)
				(justify right)
			)
		)
		(property "Voltage" "50V"
			(at 175.26 29.21 0)
			(effects
				(font
					(size 1.27 1.27)
				)
				(justify left bottom)
				(hide yes)
			)
		)
		(property "Dielectric" "X5R"
			(at 177.8 29.21 0)
			(effects
				(font
					(size 1.27 1.27)
				)
				(justify left bottom)
				(hide yes)
			)
		)
		(property "Public" "False"
			(at 180.34 29.21 0)
			(effects
				(font
					(size 1.27 1.27)
				)
				(justify left bottom)
				(hide yes)
			)
		)
		(pin "1"
		)
		(pin "2"
		)
		(instances
			(project "jetson-orin-baseboard-oculink-expansion"
				(path ""
					(reference "C18")
					(unit 1)
				)
			)
		)
	)
	(symbol
		(lib_id "antmicroResistors0402:R_1k_0402")
		(at 152.4 130.81 90)
		(unit 1)
		(exclude_from_sim no)
		(in_bom yes)
		(on_board yes)
		(dnp yes)
		(property "Reference" "R22"
			(at 152.4 134.62 0)
			(effects
				(font
					(size 1.27 1.27)
					(thickness 0.15)
				)
				(justify right)
			)
		)
		(property "Value" "R_1k_0402"
			(at 165.1 110.49 0)
			(effects
				(font
					(size 1.27 1.27)
					(thickness 0.15)
				)
				(justify left bottom)
				(hide yes)
			)
		)
		(property "Footprint" "antmicro-footprints:R_0402_1005Metric"
			(at 167.64 110.49 0)
			(effects
				(font
					(size 1.27 1.27)
					(thickness 0.15)
				)
				(justify left bottom)
				(hide yes)
			)
		)
		(property "Datasheet" "https://www.bourns.com/docs/product-datasheets/cr.pdf"
			(at 170.18 110.49 0)
			(effects
				(font
					(size 1.27 1.27)
					(thickness 0.15)
				)
				(justify left bottom)
				(hide yes)
			)
		)
		(property "Description" "SMD Chip Resistor, 1 kohm, ± 1%, 63 mW, 0402 [1005 Metric], Thick Film, General Purpose"
			(at 152.4 130.81 0)
			(effects
				(font
					(size 1.27 1.27)
				)
				(hide yes)
			)
		)
		(property "MPN" "CR0402-FX-1001GLF"
			(at 172.72 110.49 0)
			(effects
				(font
					(size 1.27 1.27)
					(thickness 0.15)
				)
				(justify left bottom)
				(hide yes)
			)
		)
		(property "Manufacturer" "Bourns"
			(at 175.26 110.49 0)
			(effects
				(font
					(size 1.27 1.27)
					(thickness 0.15)
				)
				(justify left bottom)
				(hide yes)
			)
		)
		(property "License" "Apache-2.0"
			(at 177.8 110.49 0)
			(effects
				(font
					(size 1.27 1.27)
					(thickness 0.15)
				)
				(justify left bottom)
				(hide yes)
			)
		)
		(property "Author" "Antmicro"
			(at 180.34 110.49 0)
			(effects
				(font
					(size 1.27 1.27)
					(thickness 0.15)
				)
				(justify left bottom)
				(hide yes)
			)
		)
		(property "Val" "1k"
			(at 151.13 130.81 0)
			(effects
				(font
					(size 1.27 1.27)
					(thickness 0.15)
				)
				(justify right)
			)
		)
		(property "Tolerance" "1%"
			(at 162.56 110.49 0)
			(effects
				(font
					(size 1.27 1.27)
				)
				(justify left bottom)
				(hide yes)
			)
		)
		(property "Public" "False"
			(at 182.88 110.49 0)
			(effects
				(font
					(size 1.27 1.27)
				)
				(justify left bottom)
				(hide yes)
			)
		)
		(pin "1"
		)
		(pin "2"
		)
		(instances
			(project "jetson-orin-baseboard-oculink-expansion"
				(path ""
					(reference "R22")
					(unit 1)
				)
			)
		)
	)
	(symbol
		(lib_id "antmicroCapacitors0402:C_220n_0402")
		(at 170.18 204.47 0)
		(unit 1)
		(exclude_from_sim no)
		(in_bom yes)
		(on_board yes)
		(dnp no)
		(property "Reference" "C37"
			(at 168.91 205.74 0)
			(effects
				(font
					(size 1.27 1.27)
					(thickness 0.15)
				)
			)
		)
		(property "Value" "C_220n_0402"
			(at 190.5 214.63 0)
			(effects
				(font
					(size 1.27 1.27)
					(thickness 0.15)
				)
				(justify left bottom)
				(hide yes)
			)
		)
		(property "Footprint" "antmicro-footprints:C_0402_1005Metric"
			(at 190.5 217.17 0)
			(effects
				(font
					(size 1.27 1.27)
					(thickness 0.15)
				)
				(justify left bottom)
				(hide yes)
			)
		)
		(property "Datasheet" "https://www.yageo.com/en/Chart/Download/pdf/CC0402KRX5R6BB224"
			(at 190.5 219.71 0)
			(effects
				(font
					(size 1.27 1.27)
					(thickness 0.15)
				)
				(justify left bottom)
				(hide yes)
			)
		)
		(property "Description" "SMD Multilayer Ceramic Capacitor, 0.22 µF, 10 V, 0402 [1005 Metric], ± 10%, X5R, CC Series"
			(at 170.18 204.47 0)
			(effects
				(font
					(size 1.27 1.27)
				)
				(hide yes)
			)
		)
		(property "MPN" "CC0402KRX5R6BB224"
			(at 190.5 222.25 0)
			(effects
				(font
					(size 1.27 1.27)
					(thickness 0.15)
				)
				(justify left bottom)
				(hide yes)
			)
		)
		(property "Manufacturer" "YAGEO"
			(at 190.5 224.79 0)
			(effects
				(font
					(size 1.27 1.27)
					(thickness 0.15)
				)
				(justify left bottom)
				(hide yes)
			)
		)
		(property "License" "Apache-2.0"
			(at 190.5 227.33 0)
			(effects
				(font
					(size 1.27 1.27)
					(thickness 0.15)
				)
				(justify left bottom)
				(hide yes)
			)
		)
		(property "Author" "Antmicro"
			(at 190.5 229.87 0)
			(effects
				(font
					(size 1.27 1.27)
					(thickness 0.15)
				)
				(justify left bottom)
				(hide yes)
			)
		)
		(property "Val" "220n"
			(at 176.53 205.74 0)
			(effects
				(font
					(size 1.27 1.27)
					(thickness 0.15)
				)
			)
		)
		(property "Voltage" ""
			(at 190.5 232.41 0)
			(effects
				(font
					(size 1.27 1.27)
				)
				(justify left bottom)
				(hide yes)
			)
		)
		(property "Dielectric" ""
			(at 190.5 234.95 0)
			(effects
				(font
					(size 1.27 1.27)
				)
				(justify left bottom)
				(hide yes)
			)
		)
		(property "Public" "False"
			(at 190.5 237.49 0)
			(effects
				(font
					(size 1.27 1.27)
				)
				(justify left bottom)
				(hide yes)
			)
		)
		(pin "1"
		)
		(pin "2"
		)
		(instances
			(project "jetson-orin-baseboard-oculink-expansion"
				(path ""
					(reference "C37")
					(unit 1)
				)
			)
		)
	)
	(symbol
		(lib_id "antmicropower:+3.3V")
		(at 339.09 38.1 0)
		(unit 1)
		(exclude_from_sim no)
		(in_bom yes)
		(on_board yes)
		(dnp no)
		(property "Reference" "#PWR070"
			(at 339.09 41.91 0)
			(effects
				(font
					(size 1.27 1.27)
				)
				(hide yes)
			)
		)
		(property "Value" "+5V_OCU"
			(at 339.09 33.02 0)
			(effects
				(font
					(size 1.27 1.27)
				)
			)
		)
		(property "Footprint" ""
			(at 339.09 38.1 0)
			(effects
				(font
					(size 1.27 1.27)
				)
				(hide yes)
			)
		)
		(property "Datasheet" ""
			(at 339.09 38.1 0)
			(effects
				(font
					(size 1.27 1.27)
				)
				(hide yes)
			)
		)
		(property "Description" ""
			(at 339.09 38.1 0)
			(effects
				(font
					(size 1.27 1.27)
				)
				(hide yes)
			)
		)
		(pin "1"
		)
		(instances
			(project "jetson-orin-baseboard-oculink-expansion"
				(path ""
					(reference "#PWR070")
					(unit 1)
				)
			)
		)
	)
	(symbol
		(lib_id "antmicropower:GND")
		(at 173.99 34.29 0)
		(unit 1)
		(exclude_from_sim no)
		(in_bom yes)
		(on_board yes)
		(dnp no)
		(property "Reference" "#PWR046"
			(at 182.88 36.83 0)
			(effects
				(font
					(size 1.27 1.27)
					(thickness 0.15)
				)
				(justify left bottom)
				(hide yes)
			)
		)
		(property "Value" "GND"
			(at 173.99 38.1 0)
			(effects
				(font
					(size 1.27 1.27)
					(thickness 0.15)
				)
			)
		)
		(property "Footprint" ""
			(at 182.88 41.91 0)
			(effects
				(font
					(size 1.27 1.27)
					(thickness 0.15)
				)
				(justify left bottom)
				(hide yes)
			)
		)
		(property "Datasheet" ""
			(at 182.88 46.99 0)
			(effects
				(font
					(size 1.27 1.27)
					(thickness 0.15)
				)
				(justify left bottom)
				(hide yes)
			)
		)
		(property "Description" ""
			(at 173.99 34.29 0)
			(effects
				(font
					(size 1.27 1.27)
				)
				(hide yes)
			)
		)
		(property "Author" "Antmicro"
			(at 182.88 41.91 0)
			(effects
				(font
					(size 1.27 1.27)
					(thickness 0.15)
				)
				(justify left bottom)
				(hide yes)
			)
		)
		(property "License" "Apache-2.0"
			(at 182.88 44.45 0)
			(effects
				(font
					(size 1.27 1.27)
					(thickness 0.15)
				)
				(justify left bottom)
				(hide yes)
			)
		)
		(pin "1"
		)
		(instances
			(project "jetson-orin-baseboard-oculink-expansion"
				(path ""
					(reference "#PWR046")
					(unit 1)
				)
			)
		)
	)
	(symbol
		(lib_id "antmicroResistors0402:R_1k_0402")
		(at 162.56 101.6 270)
		(unit 1)
		(exclude_from_sim no)
		(in_bom yes)
		(on_board yes)
		(dnp no)
		(property "Reference" "R29"
			(at 162.56 97.79 0)
			(effects
				(font
					(size 1.27 1.27)
					(thickness 0.15)
				)
				(justify right)
			)
		)
		(property "Value" "R_1k_0402"
			(at 149.86 121.92 0)
			(effects
				(font
					(size 1.27 1.27)
					(thickness 0.15)
				)
				(justify left bottom)
				(hide yes)
			)
		)
		(property "Footprint" "antmicro-footprints:R_0402_1005Metric"
			(at 147.32 121.92 0)
			(effects
				(font
					(size 1.27 1.27)
					(thickness 0.15)
				)
				(justify left bottom)
				(hide yes)
			)
		)
		(property "Datasheet" "https://www.bourns.com/docs/product-datasheets/cr.pdf"
			(at 144.78 121.92 0)
			(effects
				(font
					(size 1.27 1.27)
					(thickness 0.15)
				)
				(justify left bottom)
				(hide yes)
			)
		)
		(property "Description" "SMD Chip Resistor, 1 kohm, ± 1%, 63 mW, 0402 [1005 Metric], Thick Film, General Purpose"
			(at 162.56 101.6 0)
			(effects
				(font
					(size 1.27 1.27)
				)
				(hide yes)
			)
		)
		(property "MPN" "CR0402-FX-1001GLF"
			(at 142.24 121.92 0)
			(effects
				(font
					(size 1.27 1.27)
					(thickness 0.15)
				)
				(justify left bottom)
				(hide yes)
			)
		)
		(property "Manufacturer" "Bourns"
			(at 139.7 121.92 0)
			(effects
				(font
					(size 1.27 1.27)
					(thickness 0.15)
				)
				(justify left bottom)
				(hide yes)
			)
		)
		(property "License" "Apache-2.0"
			(at 137.16 121.92 0)
			(effects
				(font
					(size 1.27 1.27)
					(thickness 0.15)
				)
				(justify left bottom)
				(hide yes)
			)
		)
		(property "Author" "Antmicro"
			(at 134.62 121.92 0)
			(effects
				(font
					(size 1.27 1.27)
					(thickness 0.15)
				)
				(justify left bottom)
				(hide yes)
			)
		)
		(property "Val" "1k"
			(at 163.83 101.6 0)
			(effects
				(font
					(size 1.27 1.27)
					(thickness 0.15)
				)
				(justify right)
			)
		)
		(property "Tolerance" "1%"
			(at 152.4 121.92 0)
			(effects
				(font
					(size 1.27 1.27)
				)
				(justify left bottom)
				(hide yes)
			)
		)
		(property "Public" "False"
			(at 132.08 121.92 0)
			(effects
				(font
					(size 1.27 1.27)
				)
				(justify left bottom)
				(hide yes)
			)
		)
		(pin "1"
		)
		(pin "2"
		)
		(instances
			(project "jetson-orin-baseboard-oculink-expansion"
				(path ""
					(reference "R29")
					(unit 1)
				)
			)
		)
	)
	(symbol
		(lib_id "antmicropower:+3.3V")
		(at 321.31 38.1 0)
		(unit 1)
		(exclude_from_sim no)
		(in_bom yes)
		(on_board yes)
		(dnp no)
		(property "Reference" "#PWR071"
			(at 321.31 41.91 0)
			(effects
				(font
					(size 1.27 1.27)
				)
				(hide yes)
			)
		)
		(property "Value" "+3V3_OCU"
			(at 321.31 33.02 0)
			(effects
				(font
					(size 1.27 1.27)
				)
			)
		)
		(property "Footprint" ""
			(at 321.31 38.1 0)
			(effects
				(font
					(size 1.27 1.27)
				)
				(hide yes)
			)
		)
		(property "Datasheet" ""
			(at 321.31 38.1 0)
			(effects
				(font
					(size 1.27 1.27)
				)
				(hide yes)
			)
		)
		(property "Description" ""
			(at 321.31 38.1 0)
			(effects
				(font
					(size 1.27 1.27)
				)
				(hide yes)
			)
		)
		(pin "1"
		)
		(instances
			(project "jetson-orin-baseboard-oculink-expansion"
				(path ""
					(reference "#PWR071")
					(unit 1)
				)
			)
		)
	)
	(symbol
		(lib_id "antmicroCapacitors0402:C_10u_0402")
		(at 242.57 123.19 90)
		(unit 1)
		(exclude_from_sim no)
		(in_bom yes)
		(on_board yes)
		(dnp no)
		(property "Reference" "C16"
			(at 244.348 119.38 90)
			(effects
				(font
					(size 1.27 1.27)
					(thickness 0.15)
				)
				(justify right)
			)
		)
		(property "Value" "C_10u_0402"
			(at 252.73 102.87 0)
			(effects
				(font
					(size 1.27 1.27)
					(thickness 0.15)
				)
				(justify left bottom)
				(hide yes)
			)
		)
		(property "Footprint" "antmicro-footprints:C_0402_1005Metric"
			(at 255.27 102.87 0)
			(effects
				(font
					(size 1.27 1.27)
					(thickness 0.15)
				)
				(justify left bottom)
				(hide yes)
			)
		)
		(property "Datasheet" "https://www.yageo.com/en/Chart/Download/pdf/CC0402MRX5R5BB106"
			(at 257.81 102.87 0)
			(effects
				(font
					(size 1.27 1.27)
					(thickness 0.15)
				)
				(justify left bottom)
				(hide yes)
			)
		)
		(property "Description" "SMD Multilayer Ceramic Capacitor, 10 µF, 6.3 V, 0402 [1005 Metric], ± 20%, X5R, CC Series"
			(at 242.57 123.19 0)
			(effects
				(font
					(size 1.27 1.27)
				)
				(hide yes)
			)
		)
		(property "MPN" "CC0402MRX5R5BB106"
			(at 260.35 102.87 0)
			(effects
				(font
					(size 1.27 1.27)
					(thickness 0.15)
				)
				(justify left bottom)
				(hide yes)
			)
		)
		(property "Manufacturer" "YAGEO"
			(at 262.89 102.87 0)
			(effects
				(font
					(size 1.27 1.27)
					(thickness 0.15)
				)
				(justify left bottom)
				(hide yes)
			)
		)
		(property "License" "Apache-2.0"
			(at 265.43 102.87 0)
			(effects
				(font
					(size 1.27 1.27)
					(thickness 0.15)
				)
				(justify left bottom)
				(hide yes)
			)
		)
		(property "Author" "Antmicro"
			(at 267.97 102.87 0)
			(effects
				(font
					(size 1.27 1.27)
					(thickness 0.15)
				)
				(justify left bottom)
				(hide yes)
			)
		)
		(property "Val" "10u"
			(at 244.348 121.92 90)
			(effects
				(font
					(size 1.27 1.27)
					(thickness 0.15)
				)
				(justify right)
			)
		)
		(property "Voltage" ""
			(at 270.51 102.87 0)
			(effects
				(font
					(size 1.27 1.27)
				)
				(justify left bottom)
				(hide yes)
			)
		)
		(property "Dielectric" ""
			(at 273.05 102.87 0)
			(effects
				(font
					(size 1.27 1.27)
				)
				(justify left bottom)
				(hide yes)
			)
		)
		(pin "1"
		)
		(pin "2"
		)
		(instances
			(project ""
				(path ""
					(reference "C16")
					(unit 1)
				)
			)
		)
	)
	(symbol
		(lib_id "antmicroResistors0402:R_0R_0402")
		(at 323.85 53.34 0)
		(unit 1)
		(exclude_from_sim no)
		(in_bom yes)
		(on_board yes)
		(dnp no)
		(property "Reference" "R35"
			(at 322.072 52.324 0)
			(effects
				(font
					(size 1.27 1.27)
					(thickness 0.15)
				)
			)
		)
		(property "Value" "R_0R_0402"
			(at 344.17 66.04 0)
			(effects
				(font
					(size 1.27 1.27)
					(thickness 0.15)
				)
				(justify left bottom)
				(hide yes)
			)
		)
		(property "Footprint" "antmicro-footprints:R_0402_1005Metric"
			(at 344.17 68.58 0)
			(effects
				(font
					(size 1.27 1.27)
					(thickness 0.15)
				)
				(justify left bottom)
				(hide yes)
			)
		)
		(property "Datasheet" "https://industrial.panasonic.com/cdbs/www-data/pdf/RDA0000/AOA0000C301.pdf"
			(at 344.17 71.12 0)
			(effects
				(font
					(size 1.27 1.27)
					(thickness 0.15)
				)
				(justify left bottom)
				(hide yes)
			)
		)
		(property "Description" "SMD Chip Resistor, Jumper, 0 ohm, 100 mW, 0402 [1005 Metric], Thick Film, General Purpose"
			(at 323.85 53.34 0)
			(effects
				(font
					(size 1.27 1.27)
				)
				(hide yes)
			)
		)
		(property "MPN" "ERJ2GE0R00X"
			(at 344.17 73.66 0)
			(effects
				(font
					(size 1.27 1.27)
					(thickness 0.15)
				)
				(justify left bottom)
				(hide yes)
			)
		)
		(property "Manufacturer" "Panasonic"
			(at 344.17 76.2 0)
			(effects
				(font
					(size 1.27 1.27)
					(thickness 0.15)
				)
				(justify left bottom)
				(hide yes)
			)
		)
		(property "License" "Apache-2.0"
			(at 344.17 78.74 0)
			(effects
				(font
					(size 1.27 1.27)
					(thickness 0.15)
				)
				(justify left bottom)
				(hide yes)
			)
		)
		(property "Author" "Antmicro"
			(at 344.17 81.28 0)
			(effects
				(font
					(size 1.27 1.27)
					(thickness 0.15)
				)
				(justify left bottom)
				(hide yes)
			)
		)
		(property "Val" "0R"
			(at 330.2 52.324 0)
			(effects
				(font
					(size 1.27 1.27)
					(thickness 0.15)
				)
			)
		)
		(property "Tolerance" "~"
			(at 344.17 63.5 0)
			(effects
				(font
					(size 1.27 1.27)
				)
				(justify left bottom)
				(hide yes)
			)
		)
		(property "Current" "1A"
			(at 344.17 83.82 0)
			(effects
				(font
					(size 1.27 1.27)
					(thickness 0.15)
				)
				(justify left bottom)
				(hide yes)
			)
		)
		(pin "1"
		)
		(pin "2"
		)
		(instances
			(project "jetson-orin-baseboard-oculink-expansion"
				(path ""
					(reference "R35")
					(unit 1)
				)
			)
		)
	)
	(symbol
		(lib_id "antmicroResistors0402:R_1k_0402")
		(at 257.81 240.03 90)
		(mirror x)
		(unit 1)
		(exclude_from_sim no)
		(in_bom yes)
		(on_board yes)
		(dnp no)
		(property "Reference" "R14"
			(at 257.81 236.22 0)
			(effects
				(font
					(size 1.27 1.27)
					(thickness 0.15)
				)
				(justify right)
			)
		)
		(property "Value" "R_1k_0402"
			(at 270.51 260.35 0)
			(effects
				(font
					(size 1.27 1.27)
					(thickness 0.15)
				)
				(justify left bottom)
				(hide yes)
			)
		)
		(property "Footprint" "antmicro-footprints:R_0402_1005Metric"
			(at 273.05 260.35 0)
			(effects
				(font
					(size 1.27 1.27)
					(thickness 0.15)
				)
				(justify left bottom)
				(hide yes)
			)
		)
		(property "Datasheet" "https://www.bourns.com/docs/product-datasheets/cr.pdf"
			(at 275.59 260.35 0)
			(effects
				(font
					(size 1.27 1.27)
					(thickness 0.15)
				)
				(justify left bottom)
				(hide yes)
			)
		)
		(property "Description" "SMD Chip Resistor, 1 kohm, ± 1%, 63 mW, 0402 [1005 Metric], Thick Film, General Purpose"
			(at 257.81 240.03 0)
			(effects
				(font
					(size 1.27 1.27)
				)
				(hide yes)
			)
		)
		(property "MPN" "CR0402-FX-1001GLF"
			(at 278.13 260.35 0)
			(effects
				(font
					(size 1.27 1.27)
					(thickness 0.15)
				)
				(justify left bottom)
				(hide yes)
			)
		)
		(property "Manufacturer" "Bourns"
			(at 280.67 260.35 0)
			(effects
				(font
					(size 1.27 1.27)
					(thickness 0.15)
				)
				(justify left bottom)
				(hide yes)
			)
		)
		(property "License" "Apache-2.0"
			(at 283.21 260.35 0)
			(effects
				(font
					(size 1.27 1.27)
					(thickness 0.15)
				)
				(justify left bottom)
				(hide yes)
			)
		)
		(property "Author" "Antmicro"
			(at 285.75 260.35 0)
			(effects
				(font
					(size 1.27 1.27)
					(thickness 0.15)
				)
				(justify left bottom)
				(hide yes)
			)
		)
		(property "Val" "1k"
			(at 256.54 240.03 0)
			(effects
				(font
					(size 1.27 1.27)
					(thickness 0.15)
				)
				(justify right)
			)
		)
		(property "Tolerance" "1%"
			(at 267.97 260.35 0)
			(effects
				(font
					(size 1.27 1.27)
				)
				(justify left bottom)
				(hide yes)
			)
		)
		(property "Public" "False"
			(at 288.29 260.35 0)
			(effects
				(font
					(size 1.27 1.27)
				)
				(justify left bottom)
				(hide yes)
			)
		)
		(pin "1"
		)
		(pin "2"
		)
		(instances
			(project "jetson-orin-baseboard-oculink-expansion"
				(path ""
					(reference "R14")
					(unit 1)
				)
			)
		)
	)
	(symbol
		(lib_id "antmicropower:GND")
		(at 73.66 132.08 0)
		(unit 1)
		(exclude_from_sim no)
		(in_bom yes)
		(on_board yes)
		(dnp no)
		(fields_autoplaced yes)
		(property "Reference" "#PWR02"
			(at 73.66 138.43 0)
			(effects
				(font
					(size 1.27 1.27)
				)
				(justify left bottom)
				(hide yes)
			)
		)
		(property "Value" "GND"
			(at 73.66 135.89 0)
			(effects
				(font
					(size 1.27 1.27)
					(thickness 0.15)
				)
			)
		)
		(property "Footprint" ""
			(at 82.55 139.7 0)
			(effects
				(font
					(size 1.27 1.27)
					(thickness 0.15)
				)
				(justify left bottom)
				(hide yes)
			)
		)
		(property "Datasheet" ""
			(at 82.55 144.78 0)
			(effects
				(font
					(size 1.27 1.27)
					(thickness 0.15)
				)
				(justify left bottom)
				(hide yes)
			)
		)
		(property "Description" ""
			(at 73.66 132.08 0)
			(effects
				(font
					(size 1.27 1.27)
				)
				(hide yes)
			)
		)
		(property "Author" "Antmicro"
			(at 82.55 139.7 0)
			(effects
				(font
					(size 1.27 1.27)
					(thickness 0.15)
				)
				(justify left bottom)
				(hide yes)
			)
		)
		(property "License" "Apache-2.0"
			(at 82.55 142.24 0)
			(effects
				(font
					(size 1.27 1.27)
					(thickness 0.15)
				)
				(justify left bottom)
				(hide yes)
			)
		)
		(pin "1"
		)
		(instances
			(project "jetson-orin-baseboard-oculink-expansion"
				(path ""
					(reference "#PWR02")
					(unit 1)
				)
			)
		)
	)
	(symbol
		(lib_id "antmicropower:GND")
		(at 146.05 187.96 0)
		(mirror y)
		(unit 1)
		(exclude_from_sim no)
		(in_bom yes)
		(on_board yes)
		(dnp no)
		(property "Reference" "#PWR041"
			(at 137.16 190.5 0)
			(effects
				(font
					(size 1.27 1.27)
					(thickness 0.15)
				)
				(justify left bottom)
				(hide yes)
			)
		)
		(property "Value" "GND"
			(at 146.05 191.77 0)
			(effects
				(font
					(size 1.27 1.27)
					(thickness 0.15)
				)
			)
		)
		(property "Footprint" ""
			(at 137.16 195.58 0)
			(effects
				(font
					(size 1.27 1.27)
					(thickness 0.15)
				)
				(justify left bottom)
				(hide yes)
			)
		)
		(property "Datasheet" ""
			(at 137.16 200.66 0)
			(effects
				(font
					(size 1.27 1.27)
					(thickness 0.15)
				)
				(justify left bottom)
				(hide yes)
			)
		)
		(property "Description" ""
			(at 146.05 187.96 0)
			(effects
				(font
					(size 1.27 1.27)
				)
				(hide yes)
			)
		)
		(property "Author" "Antmicro"
			(at 137.16 195.58 0)
			(effects
				(font
					(size 1.27 1.27)
					(thickness 0.15)
				)
				(justify left bottom)
				(hide yes)
			)
		)
		(property "License" "Apache-2.0"
			(at 137.16 198.12 0)
			(effects
				(font
					(size 1.27 1.27)
					(thickness 0.15)
				)
				(justify left bottom)
				(hide yes)
			)
		)
		(pin "1"
		)
		(instances
			(project "jetson-orin-baseboard-oculink-expansion"
				(path ""
					(reference "#PWR041")
					(unit 1)
				)
			)
		)
	)
	(symbol
		(lib_id "antmicroResistors0402:R_1k_0402")
		(at 257.81 269.24 270)
		(mirror x)
		(unit 1)
		(exclude_from_sim no)
		(in_bom yes)
		(on_board yes)
		(dnp yes)
		(property "Reference" "R15"
			(at 257.81 273.05 0)
			(effects
				(font
					(size 1.27 1.27)
					(thickness 0.15)
				)
				(justify right)
			)
		)
		(property "Value" "R_1k_0402"
			(at 245.11 248.92 0)
			(effects
				(font
					(size 1.27 1.27)
					(thickness 0.15)
				)
				(justify left bottom)
				(hide yes)
			)
		)
		(property "Footprint" "antmicro-footprints:R_0402_1005Metric"
			(at 242.57 248.92 0)
			(effects
				(font
					(size 1.27 1.27)
					(thickness 0.15)
				)
				(justify left bottom)
				(hide yes)
			)
		)
		(property "Datasheet" "https://www.bourns.com/docs/product-datasheets/cr.pdf"
			(at 240.03 248.92 0)
			(effects
				(font
					(size 1.27 1.27)
					(thickness 0.15)
				)
				(justify left bottom)
				(hide yes)
			)
		)
		(property "Description" "SMD Chip Resistor, 1 kohm, ± 1%, 63 mW, 0402 [1005 Metric], Thick Film, General Purpose"
			(at 257.81 269.24 0)
			(effects
				(font
					(size 1.27 1.27)
				)
				(hide yes)
			)
		)
		(property "MPN" "CR0402-FX-1001GLF"
			(at 237.49 248.92 0)
			(effects
				(font
					(size 1.27 1.27)
					(thickness 0.15)
				)
				(justify left bottom)
				(hide yes)
			)
		)
		(property "Manufacturer" "Bourns"
			(at 234.95 248.92 0)
			(effects
				(font
					(size 1.27 1.27)
					(thickness 0.15)
				)
				(justify left bottom)
				(hide yes)
			)
		)
		(property "License" "Apache-2.0"
			(at 232.41 248.92 0)
			(effects
				(font
					(size 1.27 1.27)
					(thickness 0.15)
				)
				(justify left bottom)
				(hide yes)
			)
		)
		(property "Author" "Antmicro"
			(at 229.87 248.92 0)
			(effects
				(font
					(size 1.27 1.27)
					(thickness 0.15)
				)
				(justify left bottom)
				(hide yes)
			)
		)
		(property "Val" "1k"
			(at 259.08 269.24 0)
			(effects
				(font
					(size 1.27 1.27)
					(thickness 0.15)
				)
				(justify right)
			)
		)
		(property "Tolerance" "1%"
			(at 247.65 248.92 0)
			(effects
				(font
					(size 1.27 1.27)
				)
				(justify left bottom)
				(hide yes)
			)
		)
		(property "Public" "False"
			(at 227.33 248.92 0)
			(effects
				(font
					(size 1.27 1.27)
				)
				(justify left bottom)
				(hide yes)
			)
		)
		(pin "1"
		)
		(pin "2"
		)
		(instances
			(project "jetson-orin-baseboard-oculink-expansion"
				(path ""
					(reference "R15")
					(unit 1)
				)
			)
		)
	)
	(symbol
		(lib_id "antmicropower:GND")
		(at 154.94 172.72 0)
		(mirror y)
		(unit 1)
		(exclude_from_sim no)
		(in_bom yes)
		(on_board yes)
		(dnp no)
		(property "Reference" "#PWR035"
			(at 146.05 175.26 0)
			(effects
				(font
					(size 1.27 1.27)
					(thickness 0.15)
				)
				(justify left bottom)
				(hide yes)
			)
		)
		(property "Value" "GND"
			(at 154.94 176.53 0)
			(effects
				(font
					(size 1.27 1.27)
					(thickness 0.15)
				)
			)
		)
		(property "Footprint" ""
			(at 146.05 180.34 0)
			(effects
				(font
					(size 1.27 1.27)
					(thickness 0.15)
				)
				(justify left bottom)
				(hide yes)
			)
		)
		(property "Datasheet" ""
			(at 146.05 185.42 0)
			(effects
				(font
					(size 1.27 1.27)
					(thickness 0.15)
				)
				(justify left bottom)
				(hide yes)
			)
		)
		(property "Description" ""
			(at 154.94 172.72 0)
			(effects
				(font
					(size 1.27 1.27)
				)
				(hide yes)
			)
		)
		(property "Author" "Antmicro"
			(at 146.05 180.34 0)
			(effects
				(font
					(size 1.27 1.27)
					(thickness 0.15)
				)
				(justify left bottom)
				(hide yes)
			)
		)
		(property "License" "Apache-2.0"
			(at 146.05 182.88 0)
			(effects
				(font
					(size 1.27 1.27)
					(thickness 0.15)
				)
				(justify left bottom)
				(hide yes)
			)
		)
		(pin "1"
		)
		(instances
			(project "jetson-orin-baseboard-oculink-expansion"
				(path ""
					(reference "#PWR035")
					(unit 1)
				)
			)
		)
	)
	(symbol
		(lib_id "antmicroResistors0402:R_1k_0402")
		(at 149.86 130.81 90)
		(unit 1)
		(exclude_from_sim no)
		(in_bom yes)
		(on_board yes)
		(dnp no)
		(property "Reference" "R19"
			(at 149.86 134.62 0)
			(effects
				(font
					(size 1.27 1.27)
					(thickness 0.15)
				)
				(justify right)
			)
		)
		(property "Value" "R_1k_0402"
			(at 162.56 110.49 0)
			(effects
				(font
					(size 1.27 1.27)
					(thickness 0.15)
				)
				(justify left bottom)
				(hide yes)
			)
		)
		(property "Footprint" "antmicro-footprints:R_0402_1005Metric"
			(at 165.1 110.49 0)
			(effects
				(font
					(size 1.27 1.27)
					(thickness 0.15)
				)
				(justify left bottom)
				(hide yes)
			)
		)
		(property "Datasheet" "https://www.bourns.com/docs/product-datasheets/cr.pdf"
			(at 167.64 110.49 0)
			(effects
				(font
					(size 1.27 1.27)
					(thickness 0.15)
				)
				(justify left bottom)
				(hide yes)
			)
		)
		(property "Description" "SMD Chip Resistor, 1 kohm, ± 1%, 63 mW, 0402 [1005 Metric], Thick Film, General Purpose"
			(at 149.86 130.81 0)
			(effects
				(font
					(size 1.27 1.27)
				)
				(hide yes)
			)
		)
		(property "MPN" "CR0402-FX-1001GLF"
			(at 170.18 110.49 0)
			(effects
				(font
					(size 1.27 1.27)
					(thickness 0.15)
				)
				(justify left bottom)
				(hide yes)
			)
		)
		(property "Manufacturer" "Bourns"
			(at 172.72 110.49 0)
			(effects
				(font
					(size 1.27 1.27)
					(thickness 0.15)
				)
				(justify left bottom)
				(hide yes)
			)
		)
		(property "License" "Apache-2.0"
			(at 175.26 110.49 0)
			(effects
				(font
					(size 1.27 1.27)
					(thickness 0.15)
				)
				(justify left bottom)
				(hide yes)
			)
		)
		(property "Author" "Antmicro"
			(at 177.8 110.49 0)
			(effects
				(font
					(size 1.27 1.27)
					(thickness 0.15)
				)
				(justify left bottom)
				(hide yes)
			)
		)
		(property "Val" "1k"
			(at 148.59 130.81 0)
			(effects
				(font
					(size 1.27 1.27)
					(thickness 0.15)
				)
				(justify right)
			)
		)
		(property "Tolerance" "1%"
			(at 160.02 110.49 0)
			(effects
				(font
					(size 1.27 1.27)
				)
				(justify left bottom)
				(hide yes)
			)
		)
		(property "Public" "False"
			(at 180.34 110.49 0)
			(effects
				(font
					(size 1.27 1.27)
				)
				(justify left bottom)
				(hide yes)
			)
		)
		(pin "1"
		)
		(pin "2"
		)
		(instances
			(project "jetson-orin-baseboard-oculink-expansion"
				(path ""
					(reference "R19")
					(unit 1)
				)
			)
		)
	)
	(symbol
		(lib_id "antmicroResistors0402:R_1k_0402")
		(at 154.94 130.81 90)
		(unit 1)
		(exclude_from_sim no)
		(in_bom yes)
		(on_board yes)
		(dnp no)
		(property "Reference" "R24"
			(at 154.94 134.62 0)
			(effects
				(font
					(size 1.27 1.27)
					(thickness 0.15)
				)
				(justify right)
			)
		)
		(property "Value" "R_1k_0402"
			(at 167.64 110.49 0)
			(effects
				(font
					(size 1.27 1.27)
					(thickness 0.15)
				)
				(justify left bottom)
				(hide yes)
			)
		)
		(property "Footprint" "antmicro-footprints:R_0402_1005Metric"
			(at 170.18 110.49 0)
			(effects
				(font
					(size 1.27 1.27)
					(thickness 0.15)
				)
				(justify left bottom)
				(hide yes)
			)
		)
		(property "Datasheet" "https://www.bourns.com/docs/product-datasheets/cr.pdf"
			(at 172.72 110.49 0)
			(effects
				(font
					(size 1.27 1.27)
					(thickness 0.15)
				)
				(justify left bottom)
				(hide yes)
			)
		)
		(property "Description" "SMD Chip Resistor, 1 kohm, ± 1%, 63 mW, 0402 [1005 Metric], Thick Film, General Purpose"
			(at 154.94 130.81 0)
			(effects
				(font
					(size 1.27 1.27)
				)
				(hide yes)
			)
		)
		(property "MPN" "CR0402-FX-1001GLF"
			(at 175.26 110.49 0)
			(effects
				(font
					(size 1.27 1.27)
					(thickness 0.15)
				)
				(justify left bottom)
				(hide yes)
			)
		)
		(property "Manufacturer" "Bourns"
			(at 177.8 110.49 0)
			(effects
				(font
					(size 1.27 1.27)
					(thickness 0.15)
				)
				(justify left bottom)
				(hide yes)
			)
		)
		(property "License" "Apache-2.0"
			(at 180.34 110.49 0)
			(effects
				(font
					(size 1.27 1.27)
					(thickness 0.15)
				)
				(justify left bottom)
				(hide yes)
			)
		)
		(property "Author" "Antmicro"
			(at 182.88 110.49 0)
			(effects
				(font
					(size 1.27 1.27)
					(thickness 0.15)
				)
				(justify left bottom)
				(hide yes)
			)
		)
		(property "Val" "1k"
			(at 153.67 130.81 0)
			(effects
				(font
					(size 1.27 1.27)
					(thickness 0.15)
				)
				(justify right)
			)
		)
		(property "Tolerance" "1%"
			(at 165.1 110.49 0)
			(effects
				(font
					(size 1.27 1.27)
				)
				(justify left bottom)
				(hide yes)
			)
		)
		(property "Public" "False"
			(at 185.42 110.49 0)
			(effects
				(font
					(size 1.27 1.27)
				)
				(justify left bottom)
				(hide yes)
			)
		)
		(pin "1"
		)
		(pin "2"
		)
		(instances
			(project "jetson-orin-baseboard-oculink-expansion"
				(path ""
					(reference "R24")
					(unit 1)
				)
			)
		)
	)
	(symbol
		(lib_id "antmicropower:GND")
		(at 173.99 49.53 0)
		(unit 1)
		(exclude_from_sim no)
		(in_bom yes)
		(on_board yes)
		(dnp no)
		(property "Reference" "#PWR047"
			(at 182.88 52.07 0)
			(effects
				(font
					(size 1.27 1.27)
					(thickness 0.15)
				)
				(justify left bottom)
				(hide yes)
			)
		)
		(property "Value" "GND"
			(at 173.99 53.34 0)
			(effects
				(font
					(size 1.27 1.27)
					(thickness 0.15)
				)
			)
		)
		(property "Footprint" ""
			(at 182.88 57.15 0)
			(effects
				(font
					(size 1.27 1.27)
					(thickness 0.15)
				)
				(justify left bottom)
				(hide yes)
			)
		)
		(property "Datasheet" ""
			(at 182.88 62.23 0)
			(effects
				(font
					(size 1.27 1.27)
					(thickness 0.15)
				)
				(justify left bottom)
				(hide yes)
			)
		)
		(property "Description" ""
			(at 173.99 49.53 0)
			(effects
				(font
					(size 1.27 1.27)
				)
				(hide yes)
			)
		)
		(property "Author" "Antmicro"
			(at 182.88 57.15 0)
			(effects
				(font
					(size 1.27 1.27)
					(thickness 0.15)
				)
				(justify left bottom)
				(hide yes)
			)
		)
		(property "License" "Apache-2.0"
			(at 182.88 59.69 0)
			(effects
				(font
					(size 1.27 1.27)
					(thickness 0.15)
				)
				(justify left bottom)
				(hide yes)
			)
		)
		(pin "1"
		)
		(instances
			(project "jetson-orin-baseboard-oculink-expansion"
				(path ""
					(reference "#PWR047")
					(unit 1)
				)
			)
		)
	)
	(symbol
		(lib_id "antmicroCapacitors0402:C_220n_0402")
		(at 172.72 209.55 0)
		(unit 1)
		(exclude_from_sim no)
		(in_bom yes)
		(on_board yes)
		(dnp no)
		(property "Reference" "C42"
			(at 171.45 208.28 0)
			(effects
				(font
					(size 1.27 1.27)
					(thickness 0.15)
				)
			)
		)
		(property "Value" "C_220n_0402"
			(at 193.04 219.71 0)
			(effects
				(font
					(size 1.27 1.27)
					(thickness 0.15)
				)
				(justify left bottom)
				(hide yes)
			)
		)
		(property "Footprint" "antmicro-footprints:C_0402_1005Metric"
			(at 193.04 222.25 0)
			(effects
				(font
					(size 1.27 1.27)
					(thickness 0.15)
				)
				(justify left bottom)
				(hide yes)
			)
		)
		(property "Datasheet" "https://www.yageo.com/en/Chart/Download/pdf/CC0402KRX5R6BB224"
			(at 193.04 224.79 0)
			(effects
				(font
					(size 1.27 1.27)
					(thickness 0.15)
				)
				(justify left bottom)
				(hide yes)
			)
		)
		(property "Description" "SMD Multilayer Ceramic Capacitor, 0.22 µF, 10 V, 0402 [1005 Metric], ± 10%, X5R, CC Series"
			(at 172.72 209.55 0)
			(effects
				(font
					(size 1.27 1.27)
				)
				(hide yes)
			)
		)
		(property "MPN" "CC0402KRX5R6BB224"
			(at 193.04 227.33 0)
			(effects
				(font
					(size 1.27 1.27)
					(thickness 0.15)
				)
				(justify left bottom)
				(hide yes)
			)
		)
		(property "Manufacturer" "YAGEO"
			(at 193.04 229.87 0)
			(effects
				(font
					(size 1.27 1.27)
					(thickness 0.15)
				)
				(justify left bottom)
				(hide yes)
			)
		)
		(property "License" "Apache-2.0"
			(at 193.04 232.41 0)
			(effects
				(font
					(size 1.27 1.27)
					(thickness 0.15)
				)
				(justify left bottom)
				(hide yes)
			)
		)
		(property "Author" "Antmicro"
			(at 193.04 234.95 0)
			(effects
				(font
					(size 1.27 1.27)
					(thickness 0.15)
				)
				(justify left bottom)
				(hide yes)
			)
		)
		(property "Val" "220n"
			(at 179.07 208.28 0)
			(effects
				(font
					(size 1.27 1.27)
					(thickness 0.15)
				)
			)
		)
		(property "Voltage" ""
			(at 193.04 237.49 0)
			(effects
				(font
					(size 1.27 1.27)
				)
				(justify left bottom)
				(hide yes)
			)
		)
		(property "Dielectric" ""
			(at 193.04 240.03 0)
			(effects
				(font
					(size 1.27 1.27)
				)
				(justify left bottom)
				(hide yes)
			)
		)
		(property "Public" "False"
			(at 193.04 242.57 0)
			(effects
				(font
					(size 1.27 1.27)
				)
				(justify left bottom)
				(hide yes)
			)
		)
		(pin "1"
		)
		(pin "2"
		)
		(instances
			(project "jetson-orin-baseboard-oculink-expansion"
				(path ""
					(reference "C42")
					(unit 1)
				)
			)
		)
	)
	(symbol
		(lib_id "antmicropower:GND")
		(at 318.77 80.01 0)
		(unit 1)
		(exclude_from_sim no)
		(in_bom yes)
		(on_board yes)
		(dnp no)
		(property "Reference" "#PWR056"
			(at 327.66 82.55 0)
			(effects
				(font
					(size 1.27 1.27)
					(thickness 0.15)
				)
				(justify left bottom)
				(hide yes)
			)
		)
		(property "Value" "GND"
			(at 318.77 83.82 0)
			(effects
				(font
					(size 1.27 1.27)
					(thickness 0.15)
				)
			)
		)
		(property "Footprint" ""
			(at 327.66 87.63 0)
			(effects
				(font
					(size 1.27 1.27)
					(thickness 0.15)
				)
				(justify left bottom)
				(hide yes)
			)
		)
		(property "Datasheet" ""
			(at 327.66 92.71 0)
			(effects
				(font
					(size 1.27 1.27)
					(thickness 0.15)
				)
				(justify left bottom)
				(hide yes)
			)
		)
		(property "Description" ""
			(at 318.77 80.01 0)
			(effects
				(font
					(size 1.27 1.27)
				)
				(hide yes)
			)
		)
		(property "Author" "Antmicro"
			(at 327.66 87.63 0)
			(effects
				(font
					(size 1.27 1.27)
					(thickness 0.15)
				)
				(justify left bottom)
				(hide yes)
			)
		)
		(property "License" "Apache-2.0"
			(at 327.66 90.17 0)
			(effects
				(font
					(size 1.27 1.27)
					(thickness 0.15)
				)
				(justify left bottom)
				(hide yes)
			)
		)
		(pin "1"
		)
		(instances
			(project "jetson-orin-baseboard-oculink-expansion"
				(path ""
					(reference "#PWR056")
					(unit 1)
				)
			)
		)
	)
	(symbol
		(lib_id "antmicroResistors0402:R_10k_0402")
		(at 328.93 207.01 90)
		(unit 1)
		(exclude_from_sim no)
		(in_bom yes)
		(on_board yes)
		(dnp no)
		(property "Reference" "R3"
			(at 330.2 203.2 90)
			(effects
				(font
					(size 1.27 1.27)
					(thickness 0.15)
				)
				(justify right)
			)
		)
		(property "Value" "R_10k_0402"
			(at 341.63 186.69 0)
			(effects
				(font
					(size 1.27 1.27)
					(thickness 0.15)
				)
				(justify left bottom)
				(hide yes)
			)
		)
		(property "Footprint" "antmicro-footprints:R_0402_1005Metric"
			(at 344.17 186.69 0)
			(effects
				(font
					(size 1.27 1.27)
					(thickness 0.15)
				)
				(justify left bottom)
				(hide yes)
			)
		)
		(property "Datasheet" "https://www.bourns.com/docs/product-datasheets/cr.pdf"
			(at 346.71 186.69 0)
			(effects
				(font
					(size 1.27 1.27)
					(thickness 0.15)
				)
				(justify left bottom)
				(hide yes)
			)
		)
		(property "Description" "SMD Chip Resistor, 10 kohm, ± 1%, 62.5 mW, 0402 [1005 Metric], Thick Film, General Purpose"
			(at 328.93 207.01 0)
			(effects
				(font
					(size 1.27 1.27)
				)
				(hide yes)
			)
		)
		(property "MPN" "CR0402-FX-1002GLF"
			(at 349.25 186.69 0)
			(effects
				(font
					(size 1.27 1.27)
					(thickness 0.15)
				)
				(justify left bottom)
				(hide yes)
			)
		)
		(property "Manufacturer" "Bourns"
			(at 351.79 186.69 0)
			(effects
				(font
					(size 1.27 1.27)
					(thickness 0.15)
				)
				(justify left bottom)
				(hide yes)
			)
		)
		(property "License" "Apache-2.0"
			(at 354.33 186.69 0)
			(effects
				(font
					(size 1.27 1.27)
					(thickness 0.15)
				)
				(justify left bottom)
				(hide yes)
			)
		)
		(property "Author" "Antmicro"
			(at 356.87 186.69 0)
			(effects
				(font
					(size 1.27 1.27)
					(thickness 0.15)
				)
				(justify left bottom)
				(hide yes)
			)
		)
		(property "Val" "10k"
			(at 330.2 205.74 90)
			(effects
				(font
					(size 1.27 1.27)
					(thickness 0.15)
				)
				(justify right)
			)
		)
		(property "Tolerance" "1%"
			(at 339.09 186.69 0)
			(effects
				(font
					(size 1.27 1.27)
				)
				(justify left bottom)
				(hide yes)
			)
		)
		(pin "2"
		)
		(pin "1"
		)
		(instances
			(project ""
				(path ""
					(reference "R3")
					(unit 1)
				)
			)
		)
	)
	(symbol
		(lib_id "antmicropower:+3.3V")
		(at 345.44 154.94 0)
		(unit 1)
		(exclude_from_sim no)
		(in_bom yes)
		(on_board yes)
		(dnp no)
		(property "Reference" "#PWR074"
			(at 345.44 158.75 0)
			(effects
				(font
					(size 1.27 1.27)
				)
				(hide yes)
			)
		)
		(property "Value" "+3V3_OCU"
			(at 345.44 149.86 0)
			(effects
				(font
					(size 1.27 1.27)
				)
			)
		)
		(property "Footprint" ""
			(at 345.44 154.94 0)
			(effects
				(font
					(size 1.27 1.27)
				)
				(hide yes)
			)
		)
		(property "Datasheet" ""
			(at 345.44 154.94 0)
			(effects
				(font
					(size 1.27 1.27)
				)
				(hide yes)
			)
		)
		(property "Description" ""
			(at 345.44 154.94 0)
			(effects
				(font
					(size 1.27 1.27)
				)
				(hide yes)
			)
		)
		(pin "1"
		)
		(instances
			(project "jetson-orin-baseboard-oculink-expansion"
				(path ""
					(reference "#PWR074")
					(unit 1)
				)
			)
		)
	)
	(symbol
		(lib_id "antmicropower:+3.3V")
		(at 313.69 165.1 0)
		(unit 1)
		(exclude_from_sim no)
		(in_bom yes)
		(on_board yes)
		(dnp no)
		(property "Reference" "#PWR072"
			(at 313.69 168.91 0)
			(effects
				(font
					(size 1.27 1.27)
				)
				(hide yes)
			)
		)
		(property "Value" "+5V_OCU"
			(at 313.69 160.02 0)
			(effects
				(font
					(size 1.27 1.27)
				)
			)
		)
		(property "Footprint" ""
			(at 313.69 165.1 0)
			(effects
				(font
					(size 1.27 1.27)
				)
				(hide yes)
			)
		)
		(property "Datasheet" ""
			(at 313.69 165.1 0)
			(effects
				(font
					(size 1.27 1.27)
				)
				(hide yes)
			)
		)
		(property "Description" ""
			(at 313.69 165.1 0)
			(effects
				(font
					(size 1.27 1.27)
				)
				(hide yes)
			)
		)
		(pin "1"
		)
		(instances
			(project "jetson-orin-baseboard-oculink-expansion"
				(path ""
					(reference "#PWR072")
					(unit 1)
				)
			)
		)
	)
	(symbol
		(lib_id "antmicroCapacitors0402:C_100n_0402")
		(at 147.32 34.29 90)
		(unit 1)
		(exclude_from_sim no)
		(in_bom yes)
		(on_board yes)
		(dnp no)
		(fields_autoplaced yes)
		(property "Reference" "C17"
			(at 149.86 30.4736 90)
			(effects
				(font
					(size 1.27 1.27)
					(thickness 0.15)
				)
				(justify right)
			)
		)
		(property "Value" "C_100n_0402"
			(at 157.48 13.97 0)
			(effects
				(font
					(size 1.27 1.27)
					(thickness 0.15)
				)
				(justify left bottom)
				(hide yes)
			)
		)
		(property "Footprint" "antmicro-footprints:C_0402_1005Metric"
			(at 160.02 13.97 0)
			(effects
				(font
					(size 1.27 1.27)
					(thickness 0.15)
				)
				(justify left bottom)
				(hide yes)
			)
		)
		(property "Datasheet" "https://www.murata.com/products/productdetail?partno=GRM155R61H104KE14%23"
			(at 162.56 13.97 0)
			(effects
				(font
					(size 1.27 1.27)
					(thickness 0.15)
				)
				(justify left bottom)
				(hide yes)
			)
		)
		(property "Description" "SMD Multilayer Ceramic Capacitor, 0.1 µF, 50 V, 0402 [1005 Metric], ± 10%, X5R, GRM Series"
			(at 147.32 34.29 0)
			(effects
				(font
					(size 1.27 1.27)
				)
				(hide yes)
			)
		)
		(property "MPN" "GRM155R61H104KE14D"
			(at 165.1 13.97 0)
			(effects
				(font
					(size 1.27 1.27)
					(thickness 0.15)
				)
				(justify left bottom)
				(hide yes)
			)
		)
		(property "Manufacturer" "Murata"
			(at 167.64 13.97 0)
			(effects
				(font
					(size 1.27 1.27)
					(thickness 0.15)
				)
				(justify left bottom)
				(hide yes)
			)
		)
		(property "License" "Apache-2.0"
			(at 170.18 13.97 0)
			(effects
				(font
					(size 1.27 1.27)
					(thickness 0.15)
				)
				(justify left bottom)
				(hide yes)
			)
		)
		(property "Author" "Antmicro"
			(at 172.72 13.97 0)
			(effects
				(font
					(size 1.27 1.27)
					(thickness 0.15)
				)
				(justify left bottom)
				(hide yes)
			)
		)
		(property "Val" "100n"
			(at 149.86 33.0136 90)
			(effects
				(font
					(size 1.27 1.27)
					(thickness 0.15)
				)
				(justify right)
			)
		)
		(property "Voltage" "50V"
			(at 175.26 13.97 0)
			(effects
				(font
					(size 1.27 1.27)
				)
				(justify left bottom)
				(hide yes)
			)
		)
		(property "Dielectric" "X5R"
			(at 177.8 13.97 0)
			(effects
				(font
					(size 1.27 1.27)
				)
				(justify left bottom)
				(hide yes)
			)
		)
		(property "Public" "False"
			(at 180.34 13.97 0)
			(effects
				(font
					(size 1.27 1.27)
				)
				(justify left bottom)
				(hide yes)
			)
		)
		(pin "1"
		)
		(pin "2"
		)
		(instances
			(project "jetson-orin-baseboard-oculink-expansion"
				(path ""
					(reference "C17")
					(unit 1)
				)
			)
		)
	)
	(symbol
		(lib_id "antmicropower:PWR_FLAG")
		(at 35.56 111.76 0)
		(unit 1)
		(exclude_from_sim no)
		(in_bom yes)
		(on_board yes)
		(dnp no)
		(property "Reference" "#FLG02"
			(at 35.56 109.855 0)
			(effects
				(font
					(size 1.27 1.27)
				)
				(hide yes)
			)
		)
		(property "Value" "PWR_FLAG"
			(at 35.814 107.95 0)
			(effects
				(font
					(size 1.27 1.27)
				)
			)
		)
		(property "Footprint" ""
			(at 35.56 111.76 0)
			(effects
				(font
					(size 1.27 1.27)
				)
				(hide yes)
			)
		)
		(property "Datasheet" ""
			(at 35.56 111.76 0)
			(effects
				(font
					(size 1.27 1.27)
				)
				(hide yes)
			)
		)
		(property "Description" ""
			(at 35.56 111.76 0)
			(effects
				(font
					(size 1.27 1.27)
				)
				(hide yes)
			)
		)
		(pin "1"
		)
		(instances
			(project "jetson-orin-baseboard-oculink-expansion"
				(path ""
					(reference "#FLG02")
					(unit 1)
				)
			)
		)
	)
	(symbol
		(lib_id "antmicroCapacitors0402:C_100n_0402")
		(at 181.61 172.72 270)
		(mirror x)
		(unit 1)
		(exclude_from_sim no)
		(in_bom yes)
		(on_board yes)
		(dnp no)
		(fields_autoplaced yes)
		(property "Reference" "C7"
			(at 179.07 168.9036 90)
			(effects
				(font
					(size 1.27 1.27)
					(thickness 0.15)
				)
				(justify right)
			)
		)
		(property "Value" "C_100n_0402"
			(at 171.45 152.4 0)
			(effects
				(font
					(size 1.27 1.27)
					(thickness 0.15)
				)
				(justify left bottom)
				(hide yes)
			)
		)
		(property "Footprint" "antmicro-footprints:C_0402_1005Metric"
			(at 168.91 152.4 0)
			(effects
				(font
					(size 1.27 1.27)
					(thickness 0.15)
				)
				(justify left bottom)
				(hide yes)
			)
		)
		(property "Datasheet" "https://www.murata.com/products/productdetail?partno=GRM155R61H104KE14%23"
			(at 166.37 152.4 0)
			(effects
				(font
					(size 1.27 1.27)
					(thickness 0.15)
				)
				(justify left bottom)
				(hide yes)
			)
		)
		(property "Description" "SMD Multilayer Ceramic Capacitor, 0.1 µF, 50 V, 0402 [1005 Metric], ± 10%, X5R, GRM Series"
			(at 181.61 172.72 0)
			(effects
				(font
					(size 1.27 1.27)
				)
				(hide yes)
			)
		)
		(property "MPN" "GRM155R61H104KE14D"
			(at 163.83 152.4 0)
			(effects
				(font
					(size 1.27 1.27)
					(thickness 0.15)
				)
				(justify left bottom)
				(hide yes)
			)
		)
		(property "Manufacturer" "Murata"
			(at 161.29 152.4 0)
			(effects
				(font
					(size 1.27 1.27)
					(thickness 0.15)
				)
				(justify left bottom)
				(hide yes)
			)
		)
		(property "License" "Apache-2.0"
			(at 158.75 152.4 0)
			(effects
				(font
					(size 1.27 1.27)
					(thickness 0.15)
				)
				(justify left bottom)
				(hide yes)
			)
		)
		(property "Author" "Antmicro"
			(at 156.21 152.4 0)
			(effects
				(font
					(size 1.27 1.27)
					(thickness 0.15)
				)
				(justify left bottom)
				(hide yes)
			)
		)
		(property "Val" "100n"
			(at 179.07 171.4436 90)
			(effects
				(font
					(size 1.27 1.27)
					(thickness 0.15)
				)
				(justify right)
			)
		)
		(property "Voltage" "50V"
			(at 153.67 152.4 0)
			(effects
				(font
					(size 1.27 1.27)
				)
				(justify left bottom)
				(hide yes)
			)
		)
		(property "Dielectric" "X5R"
			(at 151.13 152.4 0)
			(effects
				(font
					(size 1.27 1.27)
				)
				(justify left bottom)
				(hide yes)
			)
		)
		(property "Public" "False"
			(at 148.59 152.4 0)
			(effects
				(font
					(size 1.27 1.27)
				)
				(justify left bottom)
				(hide yes)
			)
		)
		(pin "1"
		)
		(pin "2"
		)
		(instances
			(project "jetson-orin-baseboard-oculink-expansion"
				(path ""
					(reference "C7")
					(unit 1)
				)
			)
		)
	)
	(symbol
		(lib_id "antmicropower:GND")
		(at 165.1 49.53 0)
		(unit 1)
		(exclude_from_sim no)
		(in_bom yes)
		(on_board yes)
		(dnp no)
		(property "Reference" "#PWR045"
			(at 173.99 52.07 0)
			(effects
				(font
					(size 1.27 1.27)
					(thickness 0.15)
				)
				(justify left bottom)
				(hide yes)
			)
		)
		(property "Value" "GND"
			(at 165.1 53.34 0)
			(effects
				(font
					(size 1.27 1.27)
					(thickness 0.15)
				)
			)
		)
		(property "Footprint" ""
			(at 173.99 57.15 0)
			(effects
				(font
					(size 1.27 1.27)
					(thickness 0.15)
				)
				(justify left bottom)
				(hide yes)
			)
		)
		(property "Datasheet" ""
			(at 173.99 62.23 0)
			(effects
				(font
					(size 1.27 1.27)
					(thickness 0.15)
				)
				(justify left bottom)
				(hide yes)
			)
		)
		(property "Description" ""
			(at 165.1 49.53 0)
			(effects
				(font
					(size 1.27 1.27)
				)
				(hide yes)
			)
		)
		(property "Author" "Antmicro"
			(at 173.99 57.15 0)
			(effects
				(font
					(size 1.27 1.27)
					(thickness 0.15)
				)
				(justify left bottom)
				(hide yes)
			)
		)
		(property "License" "Apache-2.0"
			(at 173.99 59.69 0)
			(effects
				(font
					(size 1.27 1.27)
					(thickness 0.15)
				)
				(justify left bottom)
				(hide yes)
			)
		)
		(pin "1"
		)
		(instances
			(project "jetson-orin-baseboard-oculink-expansion"
				(path ""
					(reference "#PWR045")
					(unit 1)
				)
			)
		)
	)
	(symbol
		(lib_id "antmicroResistors0402:R_1k_0402")
		(at 265.43 269.24 270)
		(mirror x)
		(unit 1)
		(exclude_from_sim no)
		(in_bom yes)
		(on_board yes)
		(dnp yes)
		(property "Reference" "R9"
			(at 265.43 273.05 0)
			(effects
				(font
					(size 1.27 1.27)
					(thickness 0.15)
				)
				(justify right)
			)
		)
		(property "Value" "R_1k_0402"
			(at 252.73 248.92 0)
			(effects
				(font
					(size 1.27 1.27)
					(thickness 0.15)
				)
				(justify left bottom)
				(hide yes)
			)
		)
		(property "Footprint" "antmicro-footprints:R_0402_1005Metric"
			(at 250.19 248.92 0)
			(effects
				(font
					(size 1.27 1.27)
					(thickness 0.15)
				)
				(justify left bottom)
				(hide yes)
			)
		)
		(property "Datasheet" "https://www.bourns.com/docs/product-datasheets/cr.pdf"
			(at 247.65 248.92 0)
			(effects
				(font
					(size 1.27 1.27)
					(thickness 0.15)
				)
				(justify left bottom)
				(hide yes)
			)
		)
		(property "Description" "SMD Chip Resistor, 1 kohm, ± 1%, 63 mW, 0402 [1005 Metric], Thick Film, General Purpose"
			(at 265.43 269.24 0)
			(effects
				(font
					(size 1.27 1.27)
				)
				(hide yes)
			)
		)
		(property "MPN" "CR0402-FX-1001GLF"
			(at 245.11 248.92 0)
			(effects
				(font
					(size 1.27 1.27)
					(thickness 0.15)
				)
				(justify left bottom)
				(hide yes)
			)
		)
		(property "Manufacturer" "Bourns"
			(at 242.57 248.92 0)
			(effects
				(font
					(size 1.27 1.27)
					(thickness 0.15)
				)
				(justify left bottom)
				(hide yes)
			)
		)
		(property "License" "Apache-2.0"
			(at 240.03 248.92 0)
			(effects
				(font
					(size 1.27 1.27)
					(thickness 0.15)
				)
				(justify left bottom)
				(hide yes)
			)
		)
		(property "Author" "Antmicro"
			(at 237.49 248.92 0)
			(effects
				(font
					(size 1.27 1.27)
					(thickness 0.15)
				)
				(justify left bottom)
				(hide yes)
			)
		)
		(property "Val" "1k"
			(at 266.7 269.24 0)
			(effects
				(font
					(size 1.27 1.27)
					(thickness 0.15)
				)
				(justify right)
			)
		)
		(property "Tolerance" "1%"
			(at 255.27 248.92 0)
			(effects
				(font
					(size 1.27 1.27)
				)
				(justify left bottom)
				(hide yes)
			)
		)
		(property "Public" "False"
			(at 234.95 248.92 0)
			(effects
				(font
					(size 1.27 1.27)
				)
				(justify left bottom)
				(hide yes)
			)
		)
		(pin "1"
		)
		(pin "2"
		)
		(instances
			(project "jetson-orin-baseboard-oculink-expansion"
				(path ""
					(reference "R9")
					(unit 1)
				)
			)
		)
	)
	(symbol
		(lib_id "antmicropower:GND")
		(at 163.83 187.96 0)
		(mirror y)
		(unit 1)
		(exclude_from_sim no)
		(in_bom yes)
		(on_board yes)
		(dnp no)
		(property "Reference" "#PWR031"
			(at 154.94 190.5 0)
			(effects
				(font
					(size 1.27 1.27)
					(thickness 0.15)
				)
				(justify left bottom)
				(hide yes)
			)
		)
		(property "Value" "GND"
			(at 163.83 191.77 0)
			(effects
				(font
					(size 1.27 1.27)
					(thickness 0.15)
				)
			)
		)
		(property "Footprint" ""
			(at 154.94 195.58 0)
			(effects
				(font
					(size 1.27 1.27)
					(thickness 0.15)
				)
				(justify left bottom)
				(hide yes)
			)
		)
		(property "Datasheet" ""
			(at 154.94 200.66 0)
			(effects
				(font
					(size 1.27 1.27)
					(thickness 0.15)
				)
				(justify left bottom)
				(hide yes)
			)
		)
		(property "Description" ""
			(at 163.83 187.96 0)
			(effects
				(font
					(size 1.27 1.27)
				)
				(hide yes)
			)
		)
		(property "Author" "Antmicro"
			(at 154.94 195.58 0)
			(effects
				(font
					(size 1.27 1.27)
					(thickness 0.15)
				)
				(justify left bottom)
				(hide yes)
			)
		)
		(property "License" "Apache-2.0"
			(at 154.94 198.12 0)
			(effects
				(font
					(size 1.27 1.27)
					(thickness 0.15)
				)
				(justify left bottom)
				(hide yes)
			)
		)
		(pin "1"
		)
		(instances
			(project "jetson-orin-baseboard-oculink-expansion"
				(path ""
					(reference "#PWR031")
					(unit 1)
				)
			)
		)
	)
	(symbol
		(lib_id "antmicroPciConnectors:OCuLink_x4_Amphenol_G14A421211112HR")
		(at 344.17 40.64 0)
		(unit 1)
		(exclude_from_sim no)
		(in_bom yes)
		(on_board yes)
		(dnp no)
		(fields_autoplaced yes)
		(property "Reference" "J1"
			(at 356.87 33.02 0)
			(effects
				(font
					(size 1.27 1.27)
					(thickness 0.15)
				)
			)
		)
		(property "Value" "OCuLink_x4_Amphenol_G14A421211112HR"
			(at 383.54 53.34 0)
			(effects
				(font
					(size 1.27 1.27)
					(thickness 0.15)
				)
				(justify left bottom)
				(hide yes)
			)
		)
		(property "Footprint" "antmicro-footprints:Amphenol_G14A421211112HR"
			(at 383.54 55.88 0)
			(effects
				(font
					(size 1.27 1.27)
					(thickness 0.15)
				)
				(justify left bottom)
				(hide yes)
			)
		)
		(property "Datasheet" "https://cdn.amphenol-cs.com/media/wysiwyg/files/drawing/g14a421x1bxxxhr.pdf"
			(at 383.54 58.42 0)
			(effects
				(font
					(size 1.27 1.27)
					(thickness 0.15)
				)
				(justify left bottom)
				(hide yes)
			)
		)
		(property "Description" "I/O Connectors OCulink, Receptacle, 0.5mm pitch, 4X, R/A SMT with shell leg SMT type, 30U\" gold plating, LCP, black, T&R packing"
			(at 344.17 40.64 0)
			(effects
				(font
					(size 1.27 1.27)
				)
				(hide yes)
			)
		)
		(property "Manufacturer" "Amphenol"
			(at 383.54 50.8 0)
			(effects
				(font
					(size 1.27 1.27)
					(thickness 0.15)
				)
				(justify left bottom)
				(hide yes)
			)
		)
		(property "MPN" "G14A421211112HR"
			(at 356.87 35.56 0)
			(effects
				(font
					(size 1.27 1.27)
					(thickness 0.15)
				)
			)
		)
		(property "Author" "Antmicro"
			(at 383.54 60.96 0)
			(effects
				(font
					(size 1.27 1.27)
					(thickness 0.15)
				)
				(justify left bottom)
				(hide yes)
			)
		)
		(property "License" "Apache-2.0"
			(at 383.54 63.5 0)
			(effects
				(font
					(size 1.27 1.27)
					(thickness 0.15)
				)
				(justify left bottom)
				(hide yes)
			)
		)
		(pin "B6"
		)
		(pin "B5"
		)
		(pin "B7"
		)
		(pin "A11"
		)
		(pin "B12"
		)
		(pin "B17"
		)
		(pin "A9"
		)
		(pin "A4"
		)
		(pin "B10"
		)
		(pin "B15"
		)
		(pin "A13"
		)
		(pin "B14"
		)
		(pin "A17"
		)
		(pin "B11"
		)
		(pin "A16"
		)
		(pin "A2"
		)
		(pin "A21"
		)
		(pin "A18"
		)
		(pin "A19"
		)
		(pin "A1"
		)
		(pin "B21"
		)
		(pin "B20"
		)
		(pin "A20"
		)
		(pin "B2"
		)
		(pin "A3"
		)
		(pin "B8"
		)
		(pin "SH"
		)
		(pin "B9"
		)
		(pin "B16"
		)
		(pin "A8"
		)
		(pin "B13"
		)
		(pin "B18"
		)
		(pin "A5"
		)
		(pin "A6"
		)
		(pin "A10"
		)
		(pin "B1"
		)
		(pin "B19"
		)
		(pin "A12"
		)
		(pin "A7"
		)
		(pin "B4"
		)
		(pin "B3"
		)
		(pin "A14"
		)
		(pin "A15"
		)
		(instances
			(project ""
				(path ""
					(reference "J1")
					(unit 1)
				)
			)
		)
	)
	(symbol
		(lib_id "antmicroCapacitors0402:C_220n_0402")
		(at 245.11 66.04 0)
		(unit 1)
		(exclude_from_sim no)
		(in_bom yes)
		(on_board yes)
		(dnp no)
		(property "Reference" "C13"
			(at 243.84 67.31 0)
			(effects
				(font
					(size 1.27 1.27)
					(thickness 0.15)
				)
			)
		)
		(property "Value" "C_220n_0402"
			(at 265.43 76.2 0)
			(effects
				(font
					(size 1.27 1.27)
					(thickness 0.15)
				)
				(justify left bottom)
				(hide yes)
			)
		)
		(property "Footprint" "antmicro-footprints:C_0402_1005Metric"
			(at 265.43 78.74 0)
			(effects
				(font
					(size 1.27 1.27)
					(thickness 0.15)
				)
				(justify left bottom)
				(hide yes)
			)
		)
		(property "Datasheet" "https://www.yageo.com/en/Chart/Download/pdf/CC0402KRX5R6BB224"
			(at 265.43 81.28 0)
			(effects
				(font
					(size 1.27 1.27)
					(thickness 0.15)
				)
				(justify left bottom)
				(hide yes)
			)
		)
		(property "Description" "SMD Multilayer Ceramic Capacitor, 0.22 µF, 10 V, 0402 [1005 Metric], ± 10%, X5R, CC Series"
			(at 245.11 66.04 0)
			(effects
				(font
					(size 1.27 1.27)
				)
				(hide yes)
			)
		)
		(property "MPN" "CC0402KRX5R6BB224"
			(at 265.43 83.82 0)
			(effects
				(font
					(size 1.27 1.27)
					(thickness 0.15)
				)
				(justify left bottom)
				(hide yes)
			)
		)
		(property "Manufacturer" "YAGEO"
			(at 265.43 86.36 0)
			(effects
				(font
					(size 1.27 1.27)
					(thickness 0.15)
				)
				(justify left bottom)
				(hide yes)
			)
		)
		(property "License" "Apache-2.0"
			(at 265.43 88.9 0)
			(effects
				(font
					(size 1.27 1.27)
					(thickness 0.15)
				)
				(justify left bottom)
				(hide yes)
			)
		)
		(property "Author" "Antmicro"
			(at 265.43 91.44 0)
			(effects
				(font
					(size 1.27 1.27)
					(thickness 0.15)
				)
				(justify left bottom)
				(hide yes)
			)
		)
		(property "Val" "220n"
			(at 251.46 67.31 0)
			(effects
				(font
					(size 1.27 1.27)
					(thickness 0.15)
				)
			)
		)
		(property "Voltage" ""
			(at 265.43 93.98 0)
			(effects
				(font
					(size 1.27 1.27)
				)
				(justify left bottom)
				(hide yes)
			)
		)
		(property "Dielectric" ""
			(at 265.43 96.52 0)
			(effects
				(font
					(size 1.27 1.27)
				)
				(justify left bottom)
				(hide yes)
			)
		)
		(property "Public" "False"
			(at 265.43 99.06 0)
			(effects
				(font
					(size 1.27 1.27)
				)
				(justify left bottom)
				(hide yes)
			)
		)
		(pin "1"
		)
		(pin "2"
		)
		(instances
			(project "jetson-orin-baseboard-oculink-expansion"
				(path ""
					(reference "C13")
					(unit 1)
				)
			)
		)
	)
	(symbol
		(lib_id "antmicropower:GND")
		(at 172.72 172.72 0)
		(mirror y)
		(unit 1)
		(exclude_from_sim no)
		(in_bom yes)
		(on_board yes)
		(dnp no)
		(property "Reference" "#PWR026"
			(at 163.83 175.26 0)
			(effects
				(font
					(size 1.27 1.27)
					(thickness 0.15)
				)
				(justify left bottom)
				(hide yes)
			)
		)
		(property "Value" "GND"
			(at 172.72 176.53 0)
			(effects
				(font
					(size 1.27 1.27)
					(thickness 0.15)
				)
			)
		)
		(property "Footprint" ""
			(at 163.83 180.34 0)
			(effects
				(font
					(size 1.27 1.27)
					(thickness 0.15)
				)
				(justify left bottom)
				(hide yes)
			)
		)
		(property "Datasheet" ""
			(at 163.83 185.42 0)
			(effects
				(font
					(size 1.27 1.27)
					(thickness 0.15)
				)
				(justify left bottom)
				(hide yes)
			)
		)
		(property "Description" ""
			(at 172.72 172.72 0)
			(effects
				(font
					(size 1.27 1.27)
				)
				(hide yes)
			)
		)
		(property "Author" "Antmicro"
			(at 163.83 180.34 0)
			(effects
				(font
					(size 1.27 1.27)
					(thickness 0.15)
				)
				(justify left bottom)
				(hide yes)
			)
		)
		(property "License" "Apache-2.0"
			(at 163.83 182.88 0)
			(effects
				(font
					(size 1.27 1.27)
					(thickness 0.15)
				)
				(justify left bottom)
				(hide yes)
			)
		)
		(pin "1"
		)
		(instances
			(project "jetson-orin-baseboard-oculink-expansion"
				(path ""
					(reference "#PWR026")
					(unit 1)
				)
			)
		)
	)
	(symbol
		(lib_id "antmicropower:+3.3V")
		(at 358.14 154.94 0)
		(unit 1)
		(exclude_from_sim no)
		(in_bom yes)
		(on_board yes)
		(dnp no)
		(property "Reference" "#PWR075"
			(at 358.14 158.75 0)
			(effects
				(font
					(size 1.27 1.27)
				)
				(hide yes)
			)
		)
		(property "Value" "+5V_OCU"
			(at 358.14 149.86 0)
			(effects
				(font
					(size 1.27 1.27)
				)
			)
		)
		(property "Footprint" ""
			(at 358.14 154.94 0)
			(effects
				(font
					(size 1.27 1.27)
				)
				(hide yes)
			)
		)
		(property "Datasheet" ""
			(at 358.14 154.94 0)
			(effects
				(font
					(size 1.27 1.27)
				)
				(hide yes)
			)
		)
		(property "Description" ""
			(at 358.14 154.94 0)
			(effects
				(font
					(size 1.27 1.27)
				)
				(hide yes)
			)
		)
		(pin "1"
		)
		(instances
			(project "jetson-orin-baseboard-oculink-expansion"
				(path ""
					(reference "#PWR075")
					(unit 1)
				)
			)
		)
	)
	(symbol
		(lib_id "antmicroTestPoints:TP_0.75mm_SMD")
		(at 198.12 101.6 0)
		(mirror y)
		(unit 1)
		(exclude_from_sim no)
		(in_bom no)
		(on_board yes)
		(dnp no)
		(property "Reference" "TP15"
			(at 191.77 101.6 0)
			(effects
				(font
					(size 1.27 1.27)
					(thickness 0.15)
				)
			)
		)
		(property "Value" "TP_0.75mm_SMD"
			(at 187.325 105.41 0)
			(effects
				(font
					(size 1.27 1.27)
					(thickness 0.15)
				)
				(justify left bottom)
				(hide yes)
			)
		)
		(property "Footprint" "antmicro-footprints:TP_SMD_0.75mm"
			(at 187.325 107.95 0)
			(effects
				(font
					(size 1.27 1.27)
					(thickness 0.15)
				)
				(justify left bottom)
				(hide yes)
			)
		)
		(property "Datasheet" ""
			(at 180.34 114.3 0)
			(effects
				(font
					(size 1.27 1.27)
					(thickness 0.15)
				)
				(justify left bottom)
				(hide yes)
			)
		)
		(property "Description" "SMT test point"
			(at 198.12 101.6 0)
			(effects
				(font
					(size 1.27 1.27)
				)
				(hide yes)
			)
		)
		(property "MPN" ""
			(at 187.325 113.03 0)
			(effects
				(font
					(size 1.27 1.27)
					(thickness 0.15)
				)
				(justify left bottom)
				(hide yes)
			)
		)
		(property "Manufacturer" ""
			(at 187.325 107.95 0)
			(effects
				(font
					(size 1.27 1.27)
					(thickness 0.15)
				)
				(justify left bottom)
				(hide yes)
			)
		)
		(property "Author" "Antmicro"
			(at 187.325 110.49 0)
			(effects
				(font
					(size 1.27 1.27)
					(thickness 0.15)
				)
				(justify left bottom)
				(hide yes)
			)
		)
		(property "License" "Apache-2.0"
			(at 187.325 113.03 0)
			(effects
				(font
					(size 1.27 1.27)
					(thickness 0.15)
				)
				(justify left bottom)
				(hide yes)
			)
		)
		(property "Public" "False"
			(at 187.96 115.57 0)
			(effects
				(font
					(size 1.27 1.27)
				)
				(justify left bottom)
				(hide yes)
			)
		)
		(pin "1"
		)
		(instances
			(project "jetson-orin-baseboard-oculink-expansion"
				(path ""
					(reference "TP15")
					(unit 1)
				)
			)
		)
	)
	(symbol
		(lib_id "antmicropower:GND")
		(at 364.49 203.2 0)
		(unit 1)
		(exclude_from_sim no)
		(in_bom yes)
		(on_board yes)
		(dnp no)
		(fields_autoplaced yes)
		(property "Reference" "#PWR012"
			(at 364.49 209.55 0)
			(effects
				(font
					(size 1.27 1.27)
				)
				(justify left bottom)
				(hide yes)
			)
		)
		(property "Value" "GND"
			(at 364.49 207.01 0)
			(effects
				(font
					(size 1.27 1.27)
					(thickness 0.15)
				)
			)
		)
		(property "Footprint" ""
			(at 373.38 210.82 0)
			(effects
				(font
					(size 1.27 1.27)
					(thickness 0.15)
				)
				(justify left bottom)
				(hide yes)
			)
		)
		(property "Datasheet" ""
			(at 373.38 215.9 0)
			(effects
				(font
					(size 1.27 1.27)
					(thickness 0.15)
				)
				(justify left bottom)
				(hide yes)
			)
		)
		(property "Description" ""
			(at 364.49 203.2 0)
			(effects
				(font
					(size 1.27 1.27)
				)
				(hide yes)
			)
		)
		(property "Author" "Antmicro"
			(at 373.38 210.82 0)
			(effects
				(font
					(size 1.27 1.27)
					(thickness 0.15)
				)
				(justify left bottom)
				(hide yes)
			)
		)
		(property "License" "Apache-2.0"
			(at 373.38 213.36 0)
			(effects
				(font
					(size 1.27 1.27)
					(thickness 0.15)
				)
				(justify left bottom)
				(hide yes)
			)
		)
		(pin "1"
		)
		(instances
			(project "jetson-orin-baseboard-oculink-expansion"
				(path ""
					(reference "#PWR012")
					(unit 1)
				)
			)
		)
	)
	(symbol
		(lib_id "antmicropower:+3.3V")
		(at 44.45 111.76 0)
		(unit 1)
		(exclude_from_sim no)
		(in_bom yes)
		(on_board yes)
		(dnp no)
		(property "Reference" "#PWR05"
			(at 44.45 115.57 0)
			(effects
				(font
					(size 1.27 1.27)
				)
				(hide yes)
			)
		)
		(property "Value" "+3V3"
			(at 44.704 107.95 0)
			(effects
				(font
					(size 1.27 1.27)
				)
			)
		)
		(property "Footprint" ""
			(at 44.45 111.76 0)
			(effects
				(font
					(size 1.27 1.27)
				)
				(hide yes)
			)
		)
		(property "Datasheet" ""
			(at 44.45 111.76 0)
			(effects
				(font
					(size 1.27 1.27)
				)
				(hide yes)
			)
		)
		(property "Description" ""
			(at 44.45 111.76 0)
			(effects
				(font
					(size 1.27 1.27)
				)
				(hide yes)
			)
		)
		(pin "1"
		)
		(instances
			(project ""
				(path ""
					(reference "#PWR05")
					(unit 1)
				)
			)
		)
	)
	(symbol
		(lib_id "antmicroResistors0402:R_10k_0402")
		(at 173.99 104.14 90)
		(unit 1)
		(exclude_from_sim no)
		(in_bom yes)
		(on_board yes)
		(dnp no)
		(property "Reference" "R34"
			(at 176.276 99.568 0)
			(effects
				(font
					(size 1.27 1.27)
					(thickness 0.15)
				)
				(justify right)
			)
		)
		(property "Value" "R_10k_0402"
			(at 186.69 83.82 0)
			(effects
				(font
					(size 1.27 1.27)
					(thickness 0.15)
				)
				(justify left bottom)
				(hide yes)
			)
		)
		(property "Footprint" "antmicro-footprints:R_0402_1005Metric"
			(at 189.23 83.82 0)
			(effects
				(font
					(size 1.27 1.27)
					(thickness 0.15)
				)
				(justify left bottom)
				(hide yes)
			)
		)
		(property "Datasheet" "https://www.bourns.com/docs/product-datasheets/cr.pdf"
			(at 191.77 83.82 0)
			(effects
				(font
					(size 1.27 1.27)
					(thickness 0.15)
				)
				(justify left bottom)
				(hide yes)
			)
		)
		(property "Description" "SMD Chip Resistor, 10 kohm, ± 1%, 62.5 mW, 0402 [1005 Metric], Thick Film, General Purpose"
			(at 173.99 104.14 0)
			(effects
				(font
					(size 1.27 1.27)
				)
				(hide yes)
			)
		)
		(property "MPN" "CR0402-FX-1002GLF"
			(at 194.31 83.82 0)
			(effects
				(font
					(size 1.27 1.27)
					(thickness 0.15)
				)
				(justify left bottom)
				(hide yes)
			)
		)
		(property "Manufacturer" "Bourns"
			(at 196.85 83.82 0)
			(effects
				(font
					(size 1.27 1.27)
					(thickness 0.15)
				)
				(justify left bottom)
				(hide yes)
			)
		)
		(property "License" "Apache-2.0"
			(at 199.39 83.82 0)
			(effects
				(font
					(size 1.27 1.27)
					(thickness 0.15)
				)
				(justify left bottom)
				(hide yes)
			)
		)
		(property "Author" "Antmicro"
			(at 201.93 83.82 0)
			(effects
				(font
					(size 1.27 1.27)
					(thickness 0.15)
				)
				(justify left bottom)
				(hide yes)
			)
		)
		(property "Val" "10k"
			(at 178.054 99.822 0)
			(effects
				(font
					(size 1.27 1.27)
					(thickness 0.15)
				)
				(justify right)
			)
		)
		(property "Tolerance" "1%"
			(at 184.15 83.82 0)
			(effects
				(font
					(size 1.27 1.27)
				)
				(justify left bottom)
				(hide yes)
			)
		)
		(pin "2"
		)
		(pin "1"
		)
		(instances
			(project "jetson-orin-baseboard-oculink-expansion"
				(path ""
					(reference "R34")
					(unit 1)
				)
			)
		)
	)
	(symbol
		(lib_id "antmicropower:GND")
		(at 276.86 132.08 0)
		(mirror y)
		(unit 1)
		(exclude_from_sim no)
		(in_bom yes)
		(on_board yes)
		(dnp no)
		(property "Reference" "#PWR063"
			(at 267.97 134.62 0)
			(effects
				(font
					(size 1.27 1.27)
					(thickness 0.15)
				)
				(justify left bottom)
				(hide yes)
			)
		)
		(property "Value" "GND"
			(at 276.86 135.89 0)
			(effects
				(font
					(size 1.27 1.27)
					(thickness 0.15)
				)
			)
		)
		(property "Footprint" ""
			(at 267.97 139.7 0)
			(effects
				(font
					(size 1.27 1.27)
					(thickness 0.15)
				)
				(justify left bottom)
				(hide yes)
			)
		)
		(property "Datasheet" ""
			(at 267.97 144.78 0)
			(effects
				(font
					(size 1.27 1.27)
					(thickness 0.15)
				)
				(justify left bottom)
				(hide yes)
			)
		)
		(property "Description" ""
			(at 276.86 132.08 0)
			(effects
				(font
					(size 1.27 1.27)
				)
				(hide yes)
			)
		)
		(property "Author" "Antmicro"
			(at 267.97 139.7 0)
			(effects
				(font
					(size 1.27 1.27)
					(thickness 0.15)
				)
				(justify left bottom)
				(hide yes)
			)
		)
		(property "License" "Apache-2.0"
			(at 267.97 142.24 0)
			(effects
				(font
					(size 1.27 1.27)
					(thickness 0.15)
				)
				(justify left bottom)
				(hide yes)
			)
		)
		(pin "1"
		)
		(instances
			(project "jetson-orin-baseboard-oculink-expansion"
				(path ""
					(reference "#PWR063")
					(unit 1)
				)
			)
		)
	)
	(symbol
		(lib_id "antmicroTestPoints:TP_0.75mm_SMD")
		(at 189.23 87.63 180)
		(unit 1)
		(exclude_from_sim no)
		(in_bom no)
		(on_board yes)
		(dnp no)
		(property "Reference" "TP3"
			(at 182.88 87.63 0)
			(effects
				(font
					(size 1.27 1.27)
					(thickness 0.15)
				)
			)
		)
		(property "Value" "TP_0.75mm_SMD"
			(at 178.435 83.82 0)
			(effects
				(font
					(size 1.27 1.27)
					(thickness 0.15)
				)
				(justify left bottom)
				(hide yes)
			)
		)
		(property "Footprint" "antmicro-footprints:TP_SMD_0.75mm"
			(at 178.435 81.28 0)
			(effects
				(font
					(size 1.27 1.27)
					(thickness 0.15)
				)
				(justify left bottom)
				(hide yes)
			)
		)
		(property "Datasheet" ""
			(at 171.45 74.93 0)
			(effects
				(font
					(size 1.27 1.27)
					(thickness 0.15)
				)
				(justify left bottom)
				(hide yes)
			)
		)
		(property "Description" "SMT test point"
			(at 189.23 87.63 0)
			(effects
				(font
					(size 1.27 1.27)
				)
				(hide yes)
			)
		)
		(property "MPN" ""
			(at 178.435 76.2 0)
			(effects
				(font
					(size 1.27 1.27)
					(thickness 0.15)
				)
				(justify left bottom)
				(hide yes)
			)
		)
		(property "Manufacturer" ""
			(at 178.435 81.28 0)
			(effects
				(font
					(size 1.27 1.27)
					(thickness 0.15)
				)
				(justify left bottom)
				(hide yes)
			)
		)
		(property "Author" "Antmicro"
			(at 178.435 78.74 0)
			(effects
				(font
					(size 1.27 1.27)
					(thickness 0.15)
				)
				(justify left bottom)
				(hide yes)
			)
		)
		(property "License" "Apache-2.0"
			(at 178.435 76.2 0)
			(effects
				(font
					(size 1.27 1.27)
					(thickness 0.15)
				)
				(justify left bottom)
				(hide yes)
			)
		)
		(property "Public" "False"
			(at 179.07 73.66 0)
			(effects
				(font
					(size 1.27 1.27)
				)
				(justify left bottom)
				(hide yes)
			)
		)
		(pin "1"
		)
		(instances
			(project "jetson-orin-baseboard-oculink-expansion"
				(path ""
					(reference "TP3")
					(unit 1)
				)
			)
		)
	)
	(symbol
		(lib_id "antmicroTestPoints:TP_0.75mm_SMD")
		(at 189.23 90.17 180)
		(unit 1)
		(exclude_from_sim no)
		(in_bom no)
		(on_board yes)
		(dnp no)
		(property "Reference" "TP4"
			(at 182.88 90.17 0)
			(effects
				(font
					(size 1.27 1.27)
					(thickness 0.15)
				)
			)
		)
		(property "Value" "TP_0.75mm_SMD"
			(at 178.435 86.36 0)
			(effects
				(font
					(size 1.27 1.27)
					(thickness 0.15)
				)
				(justify left bottom)
				(hide yes)
			)
		)
		(property "Footprint" "antmicro-footprints:TP_SMD_0.75mm"
			(at 178.435 83.82 0)
			(effects
				(font
					(size 1.27 1.27)
					(thickness 0.15)
				)
				(justify left bottom)
				(hide yes)
			)
		)
		(property "Datasheet" ""
			(at 171.45 77.47 0)
			(effects
				(font
					(size 1.27 1.27)
					(thickness 0.15)
				)
				(justify left bottom)
				(hide yes)
			)
		)
		(property "Description" "SMT test point"
			(at 189.23 90.17 0)
			(effects
				(font
					(size 1.27 1.27)
				)
				(hide yes)
			)
		)
		(property "MPN" ""
			(at 178.435 78.74 0)
			(effects
				(font
					(size 1.27 1.27)
					(thickness 0.15)
				)
				(justify left bottom)
				(hide yes)
			)
		)
		(property "Manufacturer" ""
			(at 178.435 83.82 0)
			(effects
				(font
					(size 1.27 1.27)
					(thickness 0.15)
				)
				(justify left bottom)
				(hide yes)
			)
		)
		(property "Author" "Antmicro"
			(at 178.435 81.28 0)
			(effects
				(font
					(size 1.27 1.27)
					(thickness 0.15)
				)
				(justify left bottom)
				(hide yes)
			)
		)
		(property "License" "Apache-2.0"
			(at 178.435 78.74 0)
			(effects
				(font
					(size 1.27 1.27)
					(thickness 0.15)
				)
				(justify left bottom)
				(hide yes)
			)
		)
		(property "Public" "False"
			(at 179.07 76.2 0)
			(effects
				(font
					(size 1.27 1.27)
				)
				(justify left bottom)
				(hide yes)
			)
		)
		(pin "1"
		)
		(instances
			(project "jetson-orin-baseboard-oculink-expansion"
				(path ""
					(reference "TP4")
					(unit 1)
				)
			)
		)
	)
	(symbol
		(lib_id "antmicroMechanicalParts:oshw_logo")
		(at 25.4 262.89 0)
		(unit 1)
		(exclude_from_sim no)
		(in_bom no)
		(on_board yes)
		(dnp no)
		(fields_autoplaced yes)
		(property "Reference" "N1"
			(at 31.75 260.9062 0)
			(effects
				(font
					(size 1.27 1.27)
					(thickness 0.15)
				)
				(justify left)
			)
		)
		(property "Value" "oshw_logo"
			(at 31.75 263.4462 0)
			(effects
				(font
					(size 1.27 1.27)
					(thickness 0.15)
				)
				(justify left)
			)
		)
		(property "Footprint" "antmicro-footprints:oshw-logo"
			(at 40.64 273.05 0)
			(effects
				(font
					(size 1.27 1.27)
					(thickness 0.15)
				)
				(justify left bottom)
				(hide yes)
			)
		)
		(property "Datasheet" ""
			(at 40.64 275.59 0)
			(effects
				(font
					(size 1.27 1.27)
					(thickness 0.15)
				)
				(justify left bottom)
				(hide yes)
			)
		)
		(property "Description" "Mechanical part"
			(at 25.4 262.89 0)
			(effects
				(font
					(size 1.27 1.27)
				)
				(hide yes)
			)
		)
		(property "Author" "Antmicro"
			(at 40.64 278.13 0)
			(effects
				(font
					(size 1.27 1.27)
					(thickness 0.15)
				)
				(justify left bottom)
				(hide yes)
			)
		)
		(property "License" "Apache-2.0"
			(at 40.64 280.67 0)
			(effects
				(font
					(size 1.27 1.27)
					(thickness 0.15)
				)
				(justify left bottom)
				(hide yes)
			)
		)
		(property "MPN" ""
			(at 25.4 262.89 0)
			(effects
				(font
					(size 1.27 1.27)
				)
			)
		)
		(property "Manufacturer" ""
			(at 40.64 283.21 0)
			(effects
				(font
					(size 1.27 1.27)
					(thickness 0.15)
				)
				(justify left bottom)
				(hide yes)
			)
		)
		(instances
			(project ""
				(path ""
					(reference "N1")
					(unit 1)
				)
			)
		)
	)
	(symbol
		(lib_id "antmicroPMICPowerDistributionSwitchesLoadDrivers:AP22615A_TSOT26")
		(at 260.35 166.37 0)
		(unit 1)
		(exclude_from_sim no)
		(in_bom yes)
		(on_board yes)
		(dnp no)
		(fields_autoplaced yes)
		(property "Reference" "U5"
			(at 267.97 157.48 0)
			(effects
				(font
					(size 1.27 1.27)
				)
			)
		)
		(property "Value" "~"
			(at 267.97 160.02 0)
			(effects
				(font
					(size 1.27 1.27)
				)
			)
		)
		(property "Footprint" "antmicro-footprints:TSOT23-6"
			(at 290.83 173.99 0)
			(effects
				(font
					(size 1.27 1.27)
					(thickness 0.15)
				)
				(justify left bottom)
				(hide yes)
			)
		)
		(property "Datasheet" "https://www.mouser.com/datasheet/2/115/DIOD_S_A0008958405_1-2543193.pdf"
			(at 290.83 176.53 0)
			(effects
				(font
					(size 1.27 1.27)
					(thickness 0.15)
				)
				(justify left bottom)
				(hide yes)
			)
		)
		(property "Description" "Power Load Distribution Switch, High Side, Active High, 1 Output, 5.5 V, 3.6 A, 0.04 ohm, TSOT-26-6"
			(at 260.35 166.37 0)
			(effects
				(font
					(size 1.27 1.27)
				)
				(hide yes)
			)
		)
		(property "MPN" "AP22615AWU-7"
			(at 267.97 161.29 0)
			(effects
				(font
					(size 1.27 1.27)
					(thickness 0.15)
				)
			)
		)
		(property "Manufacturer" "Diodes Incorporated"
			(at 290.83 181.61 0)
			(effects
				(font
					(size 1.27 1.27)
					(thickness 0.15)
				)
				(justify left bottom)
				(hide yes)
			)
		)
		(property "Author" "Antmicro"
			(at 290.83 184.15 0)
			(effects
				(font
					(size 1.27 1.27)
					(thickness 0.15)
				)
				(justify left bottom)
				(hide yes)
			)
		)
		(property "License" "Apache-2.0"
			(at 290.83 186.69 0)
			(effects
				(font
					(size 1.27 1.27)
					(thickness 0.15)
				)
				(justify left bottom)
				(hide yes)
			)
		)
		(pin "5"
		)
		(pin "3"
		)
		(pin "6"
		)
		(pin "1"
		)
		(pin "4"
		)
		(pin "2"
		)
		(instances
			(project "jetson-orin-baseboard-oculink-expansion"
				(path ""
					(reference "U5")
					(unit 1)
				)
			)
		)
	)
	(symbol
		(lib_id "antmicropower:GND")
		(at 242.57 124.46 0)
		(unit 1)
		(exclude_from_sim no)
		(in_bom yes)
		(on_board yes)
		(dnp no)
		(property "Reference" "#PWR065"
			(at 251.46 127 0)
			(effects
				(font
					(size 1.27 1.27)
					(thickness 0.15)
				)
				(justify left bottom)
				(hide yes)
			)
		)
		(property "Value" "GND"
			(at 242.57 128.27 0)
			(effects
				(font
					(size 1.27 1.27)
					(thickness 0.15)
				)
			)
		)
		(property "Footprint" ""
			(at 251.46 132.08 0)
			(effects
				(font
					(size 1.27 1.27)
					(thickness 0.15)
				)
				(justify left bottom)
				(hide yes)
			)
		)
		(property "Datasheet" ""
			(at 251.46 137.16 0)
			(effects
				(font
					(size 1.27 1.27)
					(thickness 0.15)
				)
				(justify left bottom)
				(hide yes)
			)
		)
		(property "Description" ""
			(at 242.57 124.46 0)
			(effects
				(font
					(size 1.27 1.27)
				)
				(hide yes)
			)
		)
		(property "Author" "Antmicro"
			(at 251.46 132.08 0)
			(effects
				(font
					(size 1.27 1.27)
					(thickness 0.15)
				)
				(justify left bottom)
				(hide yes)
			)
		)
		(property "License" "Apache-2.0"
			(at 251.46 134.62 0)
			(effects
				(font
					(size 1.27 1.27)
					(thickness 0.15)
				)
				(justify left bottom)
				(hide yes)
			)
		)
		(pin "1"
		)
		(instances
			(project "jetson-orin-baseboard-oculink-expansion"
				(path ""
					(reference "#PWR065")
					(unit 1)
				)
			)
		)
	)
	(symbol
		(lib_id "antmicroCapacitors0402:C_100n_0402")
		(at 154.94 172.72 270)
		(mirror x)
		(unit 1)
		(exclude_from_sim no)
		(in_bom yes)
		(on_board yes)
		(dnp no)
		(fields_autoplaced yes)
		(property "Reference" "C23"
			(at 152.4 168.9036 90)
			(effects
				(font
					(size 1.27 1.27)
					(thickness 0.15)
				)
				(justify right)
			)
		)
		(property "Value" "C_100n_0402"
			(at 144.78 152.4 0)
			(effects
				(font
					(size 1.27 1.27)
					(thickness 0.15)
				)
				(justify left bottom)
				(hide yes)
			)
		)
		(property "Footprint" "antmicro-footprints:C_0402_1005Metric"
			(at 142.24 152.4 0)
			(effects
				(font
					(size 1.27 1.27)
					(thickness 0.15)
				)
				(justify left bottom)
				(hide yes)
			)
		)
		(property "Datasheet" "https://www.murata.com/products/productdetail?partno=GRM155R61H104KE14%23"
			(at 139.7 152.4 0)
			(effects
				(font
					(size 1.27 1.27)
					(thickness 0.15)
				)
				(justify left bottom)
				(hide yes)
			)
		)
		(property "Description" "SMD Multilayer Ceramic Capacitor, 0.1 µF, 50 V, 0402 [1005 Metric], ± 10%, X5R, GRM Series"
			(at 154.94 172.72 0)
			(effects
				(font
					(size 1.27 1.27)
				)
				(hide yes)
			)
		)
		(property "MPN" "GRM155R61H104KE14D"
			(at 137.16 152.4 0)
			(effects
				(font
					(size 1.27 1.27)
					(thickness 0.15)
				)
				(justify left bottom)
				(hide yes)
			)
		)
		(property "Manufacturer" "Murata"
			(at 134.62 152.4 0)
			(effects
				(font
					(size 1.27 1.27)
					(thickness 0.15)
				)
				(justify left bottom)
				(hide yes)
			)
		)
		(property "License" "Apache-2.0"
			(at 132.08 152.4 0)
			(effects
				(font
					(size 1.27 1.27)
					(thickness 0.15)
				)
				(justify left bottom)
				(hide yes)
			)
		)
		(property "Author" "Antmicro"
			(at 129.54 152.4 0)
			(effects
				(font
					(size 1.27 1.27)
					(thickness 0.15)
				)
				(justify left bottom)
				(hide yes)
			)
		)
		(property "Val" "100n"
			(at 152.4 171.4436 90)
			(effects
				(font
					(size 1.27 1.27)
					(thickness 0.15)
				)
				(justify right)
			)
		)
		(property "Voltage" "50V"
			(at 127 152.4 0)
			(effects
				(font
					(size 1.27 1.27)
				)
				(justify left bottom)
				(hide yes)
			)
		)
		(property "Dielectric" "X5R"
			(at 124.46 152.4 0)
			(effects
				(font
					(size 1.27 1.27)
				)
				(justify left bottom)
				(hide yes)
			)
		)
		(property "Public" "False"
			(at 121.92 152.4 0)
			(effects
				(font
					(size 1.27 1.27)
				)
				(justify left bottom)
				(hide yes)
			)
		)
		(pin "1"
		)
		(pin "2"
		)
		(instances
			(project "jetson-orin-baseboard-oculink-expansion"
				(path ""
					(reference "C23")
					(unit 1)
				)
			)
		)
	)
	(symbol
		(lib_id "antmicroTestPoints:TP_1.5mm_SMD")
		(at 43.18 73.66 180)
		(unit 1)
		(exclude_from_sim no)
		(in_bom no)
		(on_board yes)
		(dnp no)
		(property "Reference" "TP6"
			(at 35.56 73.914 0)
			(effects
				(font
					(size 1.27 1.27)
					(thickness 0.15)
				)
				(justify right)
			)
		)
		(property "Value" "TP_1.5mm_SMD"
			(at 27.94 66.04 0)
			(effects
				(font
					(size 1.27 1.27)
					(thickness 0.15)
				)
				(justify left bottom)
				(hide yes)
			)
		)
		(property "Footprint" "antmicro-footprints:TP_SMD_1.5mm"
			(at 27.94 63.5 0)
			(effects
				(font
					(size 1.27 1.27)
					(thickness 0.15)
				)
				(justify left bottom)
				(hide yes)
			)
		)
		(property "Datasheet" ""
			(at 25.4 60.96 0)
			(effects
				(font
					(size 1.27 1.27)
					(thickness 0.15)
				)
				(justify left bottom)
				(hide yes)
			)
		)
		(property "Description" "test point, SMT"
			(at 43.18 73.66 0)
			(effects
				(font
					(size 1.27 1.27)
				)
				(hide yes)
			)
		)
		(property "MPN" ""
			(at 43.18 73.66 0)
			(effects
				(font
					(size 1.27 1.27)
				)
				(hide yes)
			)
		)
		(property "Manufacturer" ""
			(at 43.18 73.66 0)
			(effects
				(font
					(size 1.27 1.27)
				)
				(hide yes)
			)
		)
		(property "Author" "Antmicro"
			(at 27.94 58.42 0)
			(effects
				(font
					(size 1.27 1.27)
					(thickness 0.15)
				)
				(justify left bottom)
				(hide yes)
			)
		)
		(property "License" "Apache-2.0"
			(at 27.94 55.88 0)
			(effects
				(font
					(size 1.27 1.27)
					(thickness 0.15)
				)
				(justify left bottom)
				(hide yes)
			)
		)
		(pin "1"
		)
		(instances
			(project "jetson-orin-baseboard-oculink-expansion"
				(path ""
					(reference "TP6")
					(unit 1)
				)
			)
		)
	)
	(symbol
		(lib_id "antmicroCapacitors0402:C_220n_0402")
		(at 170.18 212.09 0)
		(unit 1)
		(exclude_from_sim no)
		(in_bom yes)
		(on_board yes)
		(dnp no)
		(property "Reference" "C38"
			(at 168.91 213.36 0)
			(effects
				(font
					(size 1.27 1.27)
					(thickness 0.15)
				)
			)
		)
		(property "Value" "C_220n_0402"
			(at 190.5 222.25 0)
			(effects
				(font
					(size 1.27 1.27)
					(thickness 0.15)
				)
				(justify left bottom)
				(hide yes)
			)
		)
		(property "Footprint" "antmicro-footprints:C_0402_1005Metric"
			(at 190.5 224.79 0)
			(effects
				(font
					(size 1.27 1.27)
					(thickness 0.15)
				)
				(justify left bottom)
				(hide yes)
			)
		)
		(property "Datasheet" "https://www.yageo.com/en/Chart/Download/pdf/CC0402KRX5R6BB224"
			(at 190.5 227.33 0)
			(effects
				(font
					(size 1.27 1.27)
					(thickness 0.15)
				)
				(justify left bottom)
				(hide yes)
			)
		)
		(property "Description" "SMD Multilayer Ceramic Capacitor, 0.22 µF, 10 V, 0402 [1005 Metric], ± 10%, X5R, CC Series"
			(at 170.18 212.09 0)
			(effects
				(font
					(size 1.27 1.27)
				)
				(hide yes)
			)
		)
		(property "MPN" "CC0402KRX5R6BB224"
			(at 190.5 229.87 0)
			(effects
				(font
					(size 1.27 1.27)
					(thickness 0.15)
				)
				(justify left bottom)
				(hide yes)
			)
		)
		(property "Manufacturer" "YAGEO"
			(at 190.5 232.41 0)
			(effects
				(font
					(size 1.27 1.27)
					(thickness 0.15)
				)
				(justify left bottom)
				(hide yes)
			)
		)
		(property "License" "Apache-2.0"
			(at 190.5 234.95 0)
			(effects
				(font
					(size 1.27 1.27)
					(thickness 0.15)
				)
				(justify left bottom)
				(hide yes)
			)
		)
		(property "Author" "Antmicro"
			(at 190.5 237.49 0)
			(effects
				(font
					(size 1.27 1.27)
					(thickness 0.15)
				)
				(justify left bottom)
				(hide yes)
			)
		)
		(property "Val" "220n"
			(at 176.53 213.36 0)
			(effects
				(font
					(size 1.27 1.27)
					(thickness 0.15)
				)
			)
		)
		(property "Voltage" ""
			(at 190.5 240.03 0)
			(effects
				(font
					(size 1.27 1.27)
				)
				(justify left bottom)
				(hide yes)
			)
		)
		(property "Dielectric" ""
			(at 190.5 242.57 0)
			(effects
				(font
					(size 1.27 1.27)
				)
				(justify left bottom)
				(hide yes)
			)
		)
		(property "Public" "False"
			(at 190.5 245.11 0)
			(effects
				(font
					(size 1.27 1.27)
				)
				(justify left bottom)
				(hide yes)
			)
		)
		(pin "1"
		)
		(pin "2"
		)
		(instances
			(project "jetson-orin-baseboard-oculink-expansion"
				(path ""
					(reference "C38")
					(unit 1)
				)
			)
		)
	)
	(symbol
		(lib_id "antmicropower:+3V3")
		(at 147.32 26.67 0)
		(unit 1)
		(exclude_from_sim no)
		(in_bom yes)
		(on_board yes)
		(dnp no)
		(fields_autoplaced yes)
		(property "Reference" "#PWR032"
			(at 162.56 26.67 0)
			(effects
				(font
					(size 1.27 1.27)
					(thickness 0.15)
				)
				(justify left bottom)
				(hide yes)
			)
		)
		(property "Value" "+3V3"
			(at 147.32 21.59 0)
			(effects
				(font
					(size 1.27 1.27)
					(thickness 0.15)
				)
			)
		)
		(property "Footprint" ""
			(at 162.56 34.29 0)
			(effects
				(font
					(size 1.27 1.27)
					(thickness 0.15)
				)
				(justify left bottom)
				(hide yes)
			)
		)
		(property "Datasheet" ""
			(at 162.56 36.83 0)
			(effects
				(font
					(size 1.27 1.27)
					(thickness 0.15)
				)
				(justify left bottom)
				(hide yes)
			)
		)
		(property "Description" ""
			(at 147.32 26.67 0)
			(effects
				(font
					(size 1.27 1.27)
				)
				(hide yes)
			)
		)
		(property "Author" "Antmicro"
			(at 162.56 29.21 0)
			(effects
				(font
					(size 1.27 1.27)
					(thickness 0.15)
				)
				(justify left bottom)
				(hide yes)
			)
		)
		(property "License" "Apache-2.0"
			(at 162.56 31.75 0)
			(effects
				(font
					(size 1.27 1.27)
					(thickness 0.15)
				)
				(justify left bottom)
				(hide yes)
			)
		)
		(pin "1"
		)
		(instances
			(project "jetson-orin-baseboard-oculink-expansion"
				(path ""
					(reference "#PWR032")
					(unit 1)
				)
			)
		)
	)
	(symbol
		(lib_id "antmicropower:PWR_FLAG")
		(at 57.15 29.21 0)
		(unit 1)
		(exclude_from_sim no)
		(in_bom yes)
		(on_board yes)
		(dnp no)
		(property "Reference" "#FLG03"
			(at 57.15 27.305 0)
			(effects
				(font
					(size 1.27 1.27)
				)
				(hide yes)
			)
		)
		(property "Value" "PWR_FLAG"
			(at 51.054 28.194 0)
			(effects
				(font
					(size 1.27 1.27)
				)
			)
		)
		(property "Footprint" ""
			(at 57.15 29.21 0)
			(effects
				(font
					(size 1.27 1.27)
				)
				(hide yes)
			)
		)
		(property "Datasheet" ""
			(at 57.15 29.21 0)
			(effects
				(font
					(size 1.27 1.27)
				)
				(hide yes)
			)
		)
		(property "Description" ""
			(at 57.15 29.21 0)
			(effects
				(font
					(size 1.27 1.27)
				)
				(hide yes)
			)
		)
		(pin "1"
		)
		(instances
			(project "jetson-orin-baseboard-oculink-expansion"
				(path ""
					(reference "#FLG03")
					(unit 1)
				)
			)
		)
	)
	(symbol
		(lib_id "antmicroResistors0402:R_1k_0402")
		(at 157.48 101.6 270)
		(unit 1)
		(exclude_from_sim no)
		(in_bom yes)
		(on_board yes)
		(dnp yes)
		(property "Reference" "R25"
			(at 157.48 97.79 0)
			(effects
				(font
					(size 1.27 1.27)
					(thickness 0.15)
				)
				(justify right)
			)
		)
		(property "Value" "R_1k_0402"
			(at 144.78 121.92 0)
			(effects
				(font
					(size 1.27 1.27)
					(thickness 0.15)
				)
				(justify left bottom)
				(hide yes)
			)
		)
		(property "Footprint" "antmicro-footprints:R_0402_1005Metric"
			(at 142.24 121.92 0)
			(effects
				(font
					(size 1.27 1.27)
					(thickness 0.15)
				)
				(justify left bottom)
				(hide yes)
			)
		)
		(property "Datasheet" "https://www.bourns.com/docs/product-datasheets/cr.pdf"
			(at 139.7 121.92 0)
			(effects
				(font
					(size 1.27 1.27)
					(thickness 0.15)
				)
				(justify left bottom)
				(hide yes)
			)
		)
		(property "Description" "SMD Chip Resistor, 1 kohm, ± 1%, 63 mW, 0402 [1005 Metric], Thick Film, General Purpose"
			(at 157.48 101.6 0)
			(effects
				(font
					(size 1.27 1.27)
				)
				(hide yes)
			)
		)
		(property "MPN" "CR0402-FX-1001GLF"
			(at 137.16 121.92 0)
			(effects
				(font
					(size 1.27 1.27)
					(thickness 0.15)
				)
				(justify left bottom)
				(hide yes)
			)
		)
		(property "Manufacturer" "Bourns"
			(at 134.62 121.92 0)
			(effects
				(font
					(size 1.27 1.27)
					(thickness 0.15)
				)
				(justify left bottom)
				(hide yes)
			)
		)
		(property "License" "Apache-2.0"
			(at 132.08 121.92 0)
			(effects
				(font
					(size 1.27 1.27)
					(thickness 0.15)
				)
				(justify left bottom)
				(hide yes)
			)
		)
		(property "Author" "Antmicro"
			(at 129.54 121.92 0)
			(effects
				(font
					(size 1.27 1.27)
					(thickness 0.15)
				)
				(justify left bottom)
				(hide yes)
			)
		)
		(property "Val" "1k"
			(at 158.75 101.6 0)
			(effects
				(font
					(size 1.27 1.27)
					(thickness 0.15)
				)
				(justify right)
			)
		)
		(property "Tolerance" "1%"
			(at 147.32 121.92 0)
			(effects
				(font
					(size 1.27 1.27)
				)
				(justify left bottom)
				(hide yes)
			)
		)
		(property "Public" "False"
			(at 127 121.92 0)
			(effects
				(font
					(size 1.27 1.27)
				)
				(justify left bottom)
				(hide yes)
			)
		)
		(pin "1"
		)
		(pin "2"
		)
		(instances
			(project "jetson-orin-baseboard-oculink-expansion"
				(path ""
					(reference "R25")
					(unit 1)
				)
			)
		)
	)
	(symbol
		(lib_id "antmicropower:PWR_FLAG")
		(at 337.82 40.64 90)
		(unit 1)
		(exclude_from_sim no)
		(in_bom yes)
		(on_board yes)
		(dnp no)
		(property "Reference" "#FLG06"
			(at 335.915 40.64 0)
			(effects
				(font
					(size 1.27 1.27)
				)
				(hide yes)
			)
		)
		(property "Value" "PWR_FLAG"
			(at 334.01 40.6399 90)
			(effects
				(font
					(size 1.27 1.27)
				)
				(justify left)
			)
		)
		(property "Footprint" ""
			(at 337.82 40.64 0)
			(effects
				(font
					(size 1.27 1.27)
				)
				(hide yes)
			)
		)
		(property "Datasheet" ""
			(at 337.82 40.64 0)
			(effects
				(font
					(size 1.27 1.27)
				)
				(hide yes)
			)
		)
		(property "Description" ""
			(at 337.82 40.64 0)
			(effects
				(font
					(size 1.27 1.27)
				)
				(hide yes)
			)
		)
		(pin "1"
		)
		(instances
			(project "jetson-orin-baseboard-oculink-expansion"
				(path ""
					(reference "#FLG06")
					(unit 1)
				)
			)
		)
	)
	(symbol
		(lib_id "antmicroCapacitorsmisc:C_100u_0805")
		(at 298.45 175.26 90)
		(unit 1)
		(exclude_from_sim no)
		(in_bom yes)
		(on_board yes)
		(dnp no)
		(property "Reference" "C36"
			(at 300.482 171.45 90)
			(effects
				(font
					(size 1.27 1.27)
					(thickness 0.15)
				)
				(justify right)
			)
		)
		(property "Value" "C_100u_0805"
			(at 308.61 154.94 0)
			(effects
				(font
					(size 1.27 1.27)
					(thickness 0.15)
				)
				(justify left bottom)
				(hide yes)
			)
		)
		(property "Footprint" "antmicro-footprints:C_0805_2012Metric"
			(at 311.15 154.94 0)
			(effects
				(font
					(size 1.27 1.27)
					(thickness 0.15)
				)
				(justify left bottom)
				(hide yes)
			)
		)
		(property "Datasheet" "https://www.murata.com/products/productdetail?partno=GRM21BR60J107ME15%23"
			(at 313.69 154.94 0)
			(effects
				(font
					(size 1.27 1.27)
					(thickness 0.15)
				)
				(justify left bottom)
				(hide yes)
			)
		)
		(property "Description" "SMD Multilayer Ceramic Capacitor, 100 µF, 6.3 V, 0805 [2012 Metric], ± 20%, X5R, GRM Series"
			(at 298.45 175.26 0)
			(effects
				(font
					(size 1.27 1.27)
				)
				(hide yes)
			)
		)
		(property "MPN" "GRM21BR60J107ME15L"
			(at 316.23 154.94 0)
			(effects
				(font
					(size 1.27 1.27)
					(thickness 0.15)
				)
				(justify left bottom)
				(hide yes)
			)
		)
		(property "Manufacturer" "Murata"
			(at 318.77 154.94 0)
			(effects
				(font
					(size 1.27 1.27)
					(thickness 0.15)
				)
				(justify left bottom)
				(hide yes)
			)
		)
		(property "License" "Apache-2.0"
			(at 321.31 154.94 0)
			(effects
				(font
					(size 1.27 1.27)
					(thickness 0.15)
				)
				(justify left bottom)
				(hide yes)
			)
		)
		(property "Author" "Antmicro"
			(at 323.85 154.94 0)
			(effects
				(font
					(size 1.27 1.27)
					(thickness 0.15)
				)
				(justify left bottom)
				(hide yes)
			)
		)
		(property "Val" "100u"
			(at 300.482 173.99 90)
			(effects
				(font
					(size 1.27 1.27)
					(thickness 0.15)
				)
				(justify right)
			)
		)
		(property "Voltage" ""
			(at 326.39 154.94 0)
			(effects
				(font
					(size 1.27 1.27)
				)
				(justify left bottom)
				(hide yes)
			)
		)
		(property "Dielectric" ""
			(at 328.93 154.94 0)
			(effects
				(font
					(size 1.27 1.27)
				)
				(justify left bottom)
				(hide yes)
			)
		)
		(property "Public" "False"
			(at 331.47 154.94 0)
			(effects
				(font
					(size 1.27 1.27)
				)
				(justify left bottom)
				(hide yes)
			)
		)
		(pin "2"
		)
		(pin "1"
		)
		(instances
			(project "jetson-orin-baseboard-oculink-expansion"
				(path ""
					(reference "C36")
					(unit 1)
				)
			)
		)
	)
	(symbol
		(lib_id "antmicroCapacitors0402:C_100n_0402")
		(at 165.1 49.53 90)
		(unit 1)
		(exclude_from_sim no)
		(in_bom yes)
		(on_board yes)
		(dnp no)
		(fields_autoplaced yes)
		(property "Reference" "C22"
			(at 167.64 45.7136 90)
			(effects
				(font
					(size 1.27 1.27)
					(thickness 0.15)
				)
				(justify right)
			)
		)
		(property "Value" "C_100n_0402"
			(at 175.26 29.21 0)
			(effects
				(font
					(size 1.27 1.27)
					(thickness 0.15)
				)
				(justify left bottom)
				(hide yes)
			)
		)
		(property "Footprint" "antmicro-footprints:C_0402_1005Metric"
			(at 177.8 29.21 0)
			(effects
				(font
					(size 1.27 1.27)
					(thickness 0.15)
				)
				(justify left bottom)
				(hide yes)
			)
		)
		(property "Datasheet" "https://www.murata.com/products/productdetail?partno=GRM155R61H104KE14%23"
			(at 180.34 29.21 0)
			(effects
				(font
					(size 1.27 1.27)
					(thickness 0.15)
				)
				(justify left bottom)
				(hide yes)
			)
		)
		(property "Description" "SMD Multilayer Ceramic Capacitor, 0.1 µF, 50 V, 0402 [1005 Metric], ± 10%, X5R, GRM Series"
			(at 165.1 49.53 0)
			(effects
				(font
					(size 1.27 1.27)
				)
				(hide yes)
			)
		)
		(property "MPN" "GRM155R61H104KE14D"
			(at 182.88 29.21 0)
			(effects
				(font
					(size 1.27 1.27)
					(thickness 0.15)
				)
				(justify left bottom)
				(hide yes)
			)
		)
		(property "Manufacturer" "Murata"
			(at 185.42 29.21 0)
			(effects
				(font
					(size 1.27 1.27)
					(thickness 0.15)
				)
				(justify left bottom)
				(hide yes)
			)
		)
		(property "License" "Apache-2.0"
			(at 187.96 29.21 0)
			(effects
				(font
					(size 1.27 1.27)
					(thickness 0.15)
				)
				(justify left bottom)
				(hide yes)
			)
		)
		(property "Author" "Antmicro"
			(at 190.5 29.21 0)
			(effects
				(font
					(size 1.27 1.27)
					(thickness 0.15)
				)
				(justify left bottom)
				(hide yes)
			)
		)
		(property "Val" "100n"
			(at 167.64 48.2536 90)
			(effects
				(font
					(size 1.27 1.27)
					(thickness 0.15)
				)
				(justify right)
			)
		)
		(property "Voltage" "50V"
			(at 193.04 29.21 0)
			(effects
				(font
					(size 1.27 1.27)
				)
				(justify left bottom)
				(hide yes)
			)
		)
		(property "Dielectric" "X5R"
			(at 195.58 29.21 0)
			(effects
				(font
					(size 1.27 1.27)
				)
				(justify left bottom)
				(hide yes)
			)
		)
		(property "Public" "False"
			(at 198.12 29.21 0)
			(effects
				(font
					(size 1.27 1.27)
				)
				(justify left bottom)
				(hide yes)
			)
		)
		(pin "1"
		)
		(pin "2"
		)
		(instances
			(project "jetson-orin-baseboard-oculink-expansion"
				(path ""
					(reference "C22")
					(unit 1)
				)
			)
		)
	)
	(symbol
		(lib_id "antmicropower:+1V8")
		(at 386.08 187.96 0)
		(unit 1)
		(exclude_from_sim no)
		(in_bom yes)
		(on_board yes)
		(dnp no)
		(fields_autoplaced yes)
		(property "Reference" "#PWR017"
			(at 401.32 190.5 0)
			(effects
				(font
					(size 1.27 1.27)
					(thickness 0.15)
				)
				(justify left bottom)
				(hide yes)
			)
		)
		(property "Value" "+1V8"
			(at 386.08 182.88 0)
			(effects
				(font
					(size 1.27 1.27)
					(thickness 0.15)
				)
			)
		)
		(property "Footprint" ""
			(at 401.32 195.58 0)
			(effects
				(font
					(size 1.27 1.27)
					(thickness 0.15)
				)
				(justify left bottom)
				(hide yes)
			)
		)
		(property "Datasheet" ""
			(at 401.32 198.12 0)
			(effects
				(font
					(size 1.27 1.27)
					(thickness 0.15)
				)
				(justify left bottom)
				(hide yes)
			)
		)
		(property "Description" ""
			(at 386.08 187.96 0)
			(effects
				(font
					(size 1.27 1.27)
				)
				(hide yes)
			)
		)
		(property "Author" "Antmicro"
			(at 401.32 193.04 0)
			(effects
				(font
					(size 1.27 1.27)
					(thickness 0.15)
				)
				(justify left bottom)
				(hide yes)
			)
		)
		(property "License" "Apache-2.0"
			(at 401.32 195.58 0)
			(effects
				(font
					(size 1.27 1.27)
					(thickness 0.15)
				)
				(justify left bottom)
				(hide yes)
			)
		)
		(pin "1"
		)
		(instances
			(project "jetson-orin-baseboard-oculink-expansion"
				(path ""
					(reference "#PWR017")
					(unit 1)
				)
			)
		)
	)
	(symbol
		(lib_id "antmicroCapacitors0402:C_100n_0402")
		(at 173.99 34.29 90)
		(unit 1)
		(exclude_from_sim no)
		(in_bom yes)
		(on_board yes)
		(dnp no)
		(fields_autoplaced yes)
		(property "Reference" "C25"
			(at 176.53 30.4736 90)
			(effects
				(font
					(size 1.27 1.27)
					(thickness 0.15)
				)
				(justify right)
			)
		)
		(property "Value" "C_100n_0402"
			(at 184.15 13.97 0)
			(effects
				(font
					(size 1.27 1.27)
					(thickness 0.15)
				)
				(justify left bottom)
				(hide yes)
			)
		)
		(property "Footprint" "antmicro-footprints:C_0402_1005Metric"
			(at 186.69 13.97 0)
			(effects
				(font
					(size 1.27 1.27)
					(thickness 0.15)
				)
				(justify left bottom)
				(hide yes)
			)
		)
		(property "Datasheet" "https://www.murata.com/products/productdetail?partno=GRM155R61H104KE14%23"
			(at 189.23 13.97 0)
			(effects
				(font
					(size 1.27 1.27)
					(thickness 0.15)
				)
				(justify left bottom)
				(hide yes)
			)
		)
		(property "Description" "SMD Multilayer Ceramic Capacitor, 0.1 µF, 50 V, 0402 [1005 Metric], ± 10%, X5R, GRM Series"
			(at 173.99 34.29 0)
			(effects
				(font
					(size 1.27 1.27)
				)
				(hide yes)
			)
		)
		(property "MPN" "GRM155R61H104KE14D"
			(at 191.77 13.97 0)
			(effects
				(font
					(size 1.27 1.27)
					(thickness 0.15)
				)
				(justify left bottom)
				(hide yes)
			)
		)
		(property "Manufacturer" "Murata"
			(at 194.31 13.97 0)
			(effects
				(font
					(size 1.27 1.27)
					(thickness 0.15)
				)
				(justify left bottom)
				(hide yes)
			)
		)
		(property "License" "Apache-2.0"
			(at 196.85 13.97 0)
			(effects
				(font
					(size 1.27 1.27)
					(thickness 0.15)
				)
				(justify left bottom)
				(hide yes)
			)
		)
		(property "Author" "Antmicro"
			(at 199.39 13.97 0)
			(effects
				(font
					(size 1.27 1.27)
					(thickness 0.15)
				)
				(justify left bottom)
				(hide yes)
			)
		)
		(property "Val" "100n"
			(at 176.53 33.0136 90)
			(effects
				(font
					(size 1.27 1.27)
					(thickness 0.15)
				)
				(justify right)
			)
		)
		(property "Voltage" "50V"
			(at 201.93 13.97 0)
			(effects
				(font
					(size 1.27 1.27)
				)
				(justify left bottom)
				(hide yes)
			)
		)
		(property "Dielectric" "X5R"
			(at 204.47 13.97 0)
			(effects
				(font
					(size 1.27 1.27)
				)
				(justify left bottom)
				(hide yes)
			)
		)
		(property "Public" "False"
			(at 207.01 13.97 0)
			(effects
				(font
					(size 1.27 1.27)
				)
				(justify left bottom)
				(hide yes)
			)
		)
		(pin "1"
		)
		(pin "2"
		)
		(instances
			(project "jetson-orin-baseboard-oculink-expansion"
				(path ""
					(reference "C25")
					(unit 1)
				)
			)
		)
	)
	(symbol
		(lib_id "antmicropower:GND")
		(at 298.45 176.53 0)
		(mirror y)
		(unit 1)
		(exclude_from_sim no)
		(in_bom yes)
		(on_board yes)
		(dnp no)
		(property "Reference" "#PWR073"
			(at 289.56 179.07 0)
			(effects
				(font
					(size 1.27 1.27)
					(thickness 0.15)
				)
				(justify left bottom)
				(hide yes)
			)
		)
		(property "Value" "GND"
			(at 298.45 180.34 0)
			(effects
				(font
					(size 1.27 1.27)
					(thickness 0.15)
				)
			)
		)
		(property "Footprint" ""
			(at 289.56 184.15 0)
			(effects
				(font
					(size 1.27 1.27)
					(thickness 0.15)
				)
				(justify left bottom)
				(hide yes)
			)
		)
		(property "Datasheet" ""
			(at 289.56 189.23 0)
			(effects
				(font
					(size 1.27 1.27)
					(thickness 0.15)
				)
				(justify left bottom)
				(hide yes)
			)
		)
		(property "Description" ""
			(at 298.45 176.53 0)
			(effects
				(font
					(size 1.27 1.27)
				)
				(hide yes)
			)
		)
		(property "Author" "Antmicro"
			(at 289.56 184.15 0)
			(effects
				(font
					(size 1.27 1.27)
					(thickness 0.15)
				)
				(justify left bottom)
				(hide yes)
			)
		)
		(property "License" "Apache-2.0"
			(at 289.56 186.69 0)
			(effects
				(font
					(size 1.27 1.27)
					(thickness 0.15)
				)
				(justify left bottom)
				(hide yes)
			)
		)
		(pin "1"
		)
		(instances
			(project "jetson-orin-baseboard-oculink-expansion"
				(path ""
					(reference "#PWR073")
					(unit 1)
				)
			)
		)
	)
	(symbol
		(lib_id "antmicroResistors0402:R_0R_0402")
		(at 166.37 82.55 0)
		(unit 1)
		(exclude_from_sim no)
		(in_bom yes)
		(on_board yes)
		(dnp yes)
		(property "Reference" "R45"
			(at 170.942 86.868 0)
			(effects
				(font
					(size 1.27 1.27)
					(thickness 0.15)
				)
				(justify right)
			)
		)
		(property "Value" "R_0R_0402"
			(at 186.69 95.25 0)
			(effects
				(font
					(size 1.27 1.27)
					(thickness 0.15)
				)
				(justify left bottom)
				(hide yes)
			)
		)
		(property "Footprint" "antmicro-footprints:R_0402_1005Metric"
			(at 186.69 97.79 0)
			(effects
				(font
					(size 1.27 1.27)
					(thickness 0.15)
				)
				(justify left bottom)
				(hide yes)
			)
		)
		(property "Datasheet" "https://industrial.panasonic.com/cdbs/www-data/pdf/RDA0000/AOA0000C301.pdf"
			(at 186.69 100.33 0)
			(effects
				(font
					(size 1.27 1.27)
					(thickness 0.15)
				)
				(justify left bottom)
				(hide yes)
			)
		)
		(property "Description" "SMD Chip Resistor, Jumper, 0 ohm, 100 mW, 0402 [1005 Metric], Thick Film, General Purpose"
			(at 166.37 82.55 0)
			(effects
				(font
					(size 1.27 1.27)
				)
				(hide yes)
			)
		)
		(property "MPN" "ERJ2GE0R00X"
			(at 186.69 102.87 0)
			(effects
				(font
					(size 1.27 1.27)
					(thickness 0.15)
				)
				(justify left bottom)
				(hide yes)
			)
		)
		(property "Manufacturer" "Panasonic"
			(at 186.69 105.41 0)
			(effects
				(font
					(size 1.27 1.27)
					(thickness 0.15)
				)
				(justify left bottom)
				(hide yes)
			)
		)
		(property "License" "Apache-2.0"
			(at 186.69 107.95 0)
			(effects
				(font
					(size 1.27 1.27)
					(thickness 0.15)
				)
				(justify left bottom)
				(hide yes)
			)
		)
		(property "Author" "Antmicro"
			(at 186.69 110.49 0)
			(effects
				(font
					(size 1.27 1.27)
					(thickness 0.15)
				)
				(justify left bottom)
				(hide yes)
			)
		)
		(property "Val" "0R"
			(at 169.672 85.09 0)
			(effects
				(font
					(size 1.27 1.27)
					(thickness 0.15)
				)
				(justify right)
			)
		)
		(property "Tolerance" "~"
			(at 186.69 92.71 0)
			(effects
				(font
					(size 1.27 1.27)
				)
				(justify left bottom)
				(hide yes)
			)
		)
		(property "Current" "1A"
			(at 186.69 113.03 0)
			(effects
				(font
					(size 1.27 1.27)
					(thickness 0.15)
				)
				(justify left bottom)
				(hide yes)
			)
		)
		(property "Public" "False"
			(at 186.69 113.03 0)
			(effects
				(font
					(size 1.27 1.27)
				)
				(justify left bottom)
				(hide yes)
			)
		)
		(pin "1"
		)
		(pin "2"
		)
		(instances
			(project "jetson-orin-baseboard-oculink-expansion"
				(path ""
					(reference "R45")
					(unit 1)
				)
			)
		)
	)
	(symbol
		(lib_id "antmicropower:+3V3")
		(at 146.05 163.83 0)
		(unit 1)
		(exclude_from_sim no)
		(in_bom yes)
		(on_board yes)
		(dnp no)
		(fields_autoplaced yes)
		(property "Reference" "#PWR061"
			(at 161.29 163.83 0)
			(effects
				(font
					(size 1.27 1.27)
					(thickness 0.15)
				)
				(justify left bottom)
				(hide yes)
			)
		)
		(property "Value" "+3V3"
			(at 146.05 158.75 0)
			(effects
				(font
					(size 1.27 1.27)
					(thickness 0.15)
				)
			)
		)
		(property "Footprint" ""
			(at 161.29 171.45 0)
			(effects
				(font
					(size 1.27 1.27)
					(thickness 0.15)
				)
				(justify left bottom)
				(hide yes)
			)
		)
		(property "Datasheet" ""
			(at 161.29 173.99 0)
			(effects
				(font
					(size 1.27 1.27)
					(thickness 0.15)
				)
				(justify left bottom)
				(hide yes)
			)
		)
		(property "Description" ""
			(at 146.05 163.83 0)
			(effects
				(font
					(size 1.27 1.27)
				)
				(hide yes)
			)
		)
		(property "Author" "Antmicro"
			(at 161.29 166.37 0)
			(effects
				(font
					(size 1.27 1.27)
					(thickness 0.15)
				)
				(justify left bottom)
				(hide yes)
			)
		)
		(property "License" "Apache-2.0"
			(at 161.29 168.91 0)
			(effects
				(font
					(size 1.27 1.27)
					(thickness 0.15)
				)
				(justify left bottom)
				(hide yes)
			)
		)
		(pin "1"
		)
		(instances
			(project "jetson-orin-baseboard-oculink-expansion"
				(path ""
					(reference "#PWR061")
					(unit 1)
				)
			)
		)
	)
	(symbol
		(lib_id "antmicroB2BConnectors:Plug_Samtec_ERM8_2x40_ERM8-040-05.0-L-DV-K-TR")
		(at 59.69 30.48 0)
		(unit 1)
		(exclude_from_sim no)
		(in_bom yes)
		(on_board yes)
		(dnp no)
		(fields_autoplaced yes)
		(property "Reference" "J2"
			(at 65.405 22.86 0)
			(effects
				(font
					(size 1.27 1.27)
					(thickness 0.15)
				)
			)
		)
		(property "Value" "Plug_Samtec_ERM8_2x40_ERM8-040-05.0-L-DV-K-TR"
			(at 92.71 35.56 0)
			(effects
				(font
					(size 1.27 1.27)
					(thickness 0.15)
				)
				(justify left bottom)
				(hide yes)
			)
		)
		(property "Footprint" "antmicro-footprints:Conn_Plug_Samtec_ERM8_2x40_ERM8-040-05.0-L-DV-K-TR"
			(at 92.71 38.1 0)
			(effects
				(font
					(size 1.27 1.27)
					(thickness 0.15)
				)
				(justify left bottom)
				(hide yes)
			)
		)
		(property "Datasheet" "https://suddendocs.samtec.com/catalog_english/erf8.pdf"
			(at 92.71 40.64 0)
			(effects
				(font
					(size 1.27 1.27)
					(thickness 0.15)
				)
				(justify left bottom)
				(hide yes)
			)
		)
		(property "Description" "80 Position Connector Header, Center Strip Contacts Surface Mount Gold"
			(at 59.69 30.48 0)
			(effects
				(font
					(size 1.27 1.27)
				)
				(hide yes)
			)
		)
		(property "MPN" "ERM8-040-05.0-L-DV-K-TR"
			(at 65.405 25.4 0)
			(effects
				(font
					(size 1.27 1.27)
					(thickness 0.15)
				)
			)
		)
		(property "Manufacturer" "Samtec"
			(at 92.71 43.18 0)
			(effects
				(font
					(size 1.27 1.27)
					(thickness 0.15)
				)
				(justify left bottom)
				(hide yes)
			)
		)
		(property "Author" "Antmicro"
			(at 92.71 48.26 0)
			(effects
				(font
					(size 1.27 1.27)
					(thickness 0.15)
				)
				(justify left bottom)
				(hide yes)
			)
		)
		(property "License" "Apache-2.0"
			(at 92.71 50.8 0)
			(effects
				(font
					(size 1.27 1.27)
					(thickness 0.15)
				)
				(justify left bottom)
				(hide yes)
			)
		)
		(property "Pitch" "0.8 mm"
			(at 92.71 45.72 0)
			(effects
				(font
					(size 1.27 1.27)
				)
				(justify left bottom)
				(hide yes)
			)
		)
		(pin "74"
		)
		(pin "59"
		)
		(pin "47"
		)
		(pin "30"
		)
		(pin "79"
		)
		(pin "10"
		)
		(pin "46"
		)
		(pin "75"
		)
		(pin "76"
		)
		(pin "1"
		)
		(pin "80"
		)
		(pin "4"
		)
		(pin "40"
		)
		(pin "72"
		)
		(pin "2"
		)
		(pin "70"
		)
		(pin "65"
		)
		(pin "33"
		)
		(pin "44"
		)
		(pin "67"
		)
		(pin "52"
		)
		(pin "32"
		)
		(pin "77"
		)
		(pin "38"
		)
		(pin "69"
		)
		(pin "20"
		)
		(pin "21"
		)
		(pin "71"
		)
		(pin "61"
		)
		(pin "58"
		)
		(pin "12"
		)
		(pin "18"
		)
		(pin "41"
		)
		(pin "17"
		)
		(pin "54"
		)
		(pin "28"
		)
		(pin "50"
		)
		(pin "23"
		)
		(pin "25"
		)
		(pin "48"
		)
		(pin "51"
		)
		(pin "11"
		)
		(pin "9"
		)
		(pin "55"
		)
		(pin "45"
		)
		(pin "14"
		)
		(pin "22"
		)
		(pin "64"
		)
		(pin "8"
		)
		(pin "31"
		)
		(pin "16"
		)
		(pin "15"
		)
		(pin "63"
		)
		(pin "6"
		)
		(pin "39"
		)
		(pin "62"
		)
		(pin "42"
		)
		(pin "3"
		)
		(pin "49"
		)
		(pin "73"
		)
		(pin "60"
		)
		(pin "78"
		)
		(pin "27"
		)
		(pin "34"
		)
		(pin "35"
		)
		(pin "36"
		)
		(pin "26"
		)
		(pin "56"
		)
		(pin "19"
		)
		(pin "29"
		)
		(pin "43"
		)
		(pin "68"
		)
		(pin "5"
		)
		(pin "53"
		)
		(pin "24"
		)
		(pin "7"
		)
		(pin "37"
		)
		(pin "13"
		)
		(pin "66"
		)
		(pin "57"
		)
		(instances
			(project ""
				(path ""
					(reference "J2")
					(unit 1)
				)
			)
		)
	)
	(symbol
		(lib_id "antmicroMechanicalParts:antmicro_logo")
		(at 45.72 262.89 0)
		(unit 1)
		(exclude_from_sim no)
		(in_bom no)
		(on_board yes)
		(dnp no)
		(fields_autoplaced yes)
		(property "Reference" "N2"
			(at 52.07 260.9062 0)
			(effects
				(font
					(size 1.27 1.27)
					(thickness 0.15)
				)
				(justify left)
			)
		)
		(property "Value" "antmicro_logo"
			(at 52.07 263.4462 0)
			(effects
				(font
					(size 1.27 1.27)
					(thickness 0.15)
				)
				(justify left)
			)
		)
		(property "Footprint" "antmicro-footprints:antmicro-logo_scaled_15mm"
			(at 60.96 273.05 0)
			(effects
				(font
					(size 1.27 1.27)
					(thickness 0.15)
				)
				(justify left bottom)
				(hide yes)
			)
		)
		(property "Datasheet" ""
			(at 60.96 275.59 0)
			(effects
				(font
					(size 1.27 1.27)
					(thickness 0.15)
				)
				(justify left bottom)
				(hide yes)
			)
		)
		(property "Description" "Mechanical part"
			(at 45.72 262.89 0)
			(effects
				(font
					(size 1.27 1.27)
				)
				(hide yes)
			)
		)
		(property "MPN" ""
			(at 45.72 262.89 0)
			(effects
				(font
					(size 1.27 1.27)
				)
			)
		)
		(property "Manufacturer" ""
			(at 60.96 283.21 0)
			(effects
				(font
					(size 1.27 1.27)
					(thickness 0.15)
				)
				(justify left bottom)
				(hide yes)
			)
		)
		(property "Author" "Antmicro"
			(at 60.96 278.13 0)
			(effects
				(font
					(size 1.27 1.27)
					(thickness 0.15)
				)
				(justify left bottom)
				(hide yes)
			)
		)
		(property "License" "Apache-2.0"
			(at 60.96 280.67 0)
			(effects
				(font
					(size 1.27 1.27)
					(thickness 0.15)
				)
				(justify left bottom)
				(hide yes)
			)
		)
		(instances
			(project ""
				(path ""
					(reference "N2")
					(unit 1)
				)
			)
		)
	)
	(symbol
		(lib_id "antmicroCapacitors0402:C_100n_0402")
		(at 154.94 187.96 270)
		(mirror x)
		(unit 1)
		(exclude_from_sim no)
		(in_bom yes)
		(on_board yes)
		(dnp no)
		(fields_autoplaced yes)
		(property "Reference" "C24"
			(at 152.4 184.1436 90)
			(effects
				(font
					(size 1.27 1.27)
					(thickness 0.15)
				)
				(justify right)
			)
		)
		(property "Value" "C_100n_0402"
			(at 144.78 167.64 0)
			(effects
				(font
					(size 1.27 1.27)
					(thickness 0.15)
				)
				(justify left bottom)
				(hide yes)
			)
		)
		(property "Footprint" "antmicro-footprints:C_0402_1005Metric"
			(at 142.24 167.64 0)
			(effects
				(font
					(size 1.27 1.27)
					(thickness 0.15)
				)
				(justify left bottom)
				(hide yes)
			)
		)
		(property "Datasheet" "https://www.murata.com/products/productdetail?partno=GRM155R61H104KE14%23"
			(at 139.7 167.64 0)
			(effects
				(font
					(size 1.27 1.27)
					(thickness 0.15)
				)
				(justify left bottom)
				(hide yes)
			)
		)
		(property "Description" "SMD Multilayer Ceramic Capacitor, 0.1 µF, 50 V, 0402 [1005 Metric], ± 10%, X5R, GRM Series"
			(at 154.94 187.96 0)
			(effects
				(font
					(size 1.27 1.27)
				)
				(hide yes)
			)
		)
		(property "MPN" "GRM155R61H104KE14D"
			(at 137.16 167.64 0)
			(effects
				(font
					(size 1.27 1.27)
					(thickness 0.15)
				)
				(justify left bottom)
				(hide yes)
			)
		)
		(property "Manufacturer" "Murata"
			(at 134.62 167.64 0)
			(effects
				(font
					(size 1.27 1.27)
					(thickness 0.15)
				)
				(justify left bottom)
				(hide yes)
			)
		)
		(property "License" "Apache-2.0"
			(at 132.08 167.64 0)
			(effects
				(font
					(size 1.27 1.27)
					(thickness 0.15)
				)
				(justify left bottom)
				(hide yes)
			)
		)
		(property "Author" "Antmicro"
			(at 129.54 167.64 0)
			(effects
				(font
					(size 1.27 1.27)
					(thickness 0.15)
				)
				(justify left bottom)
				(hide yes)
			)
		)
		(property "Val" "100n"
			(at 152.4 186.6836 90)
			(effects
				(font
					(size 1.27 1.27)
					(thickness 0.15)
				)
				(justify right)
			)
		)
		(property "Voltage" "50V"
			(at 127 167.64 0)
			(effects
				(font
					(size 1.27 1.27)
				)
				(justify left bottom)
				(hide yes)
			)
		)
		(property "Dielectric" "X5R"
			(at 124.46 167.64 0)
			(effects
				(font
					(size 1.27 1.27)
				)
				(justify left bottom)
				(hide yes)
			)
		)
		(property "Public" "False"
			(at 121.92 167.64 0)
			(effects
				(font
					(size 1.27 1.27)
				)
				(justify left bottom)
				(hide yes)
			)
		)
		(pin "1"
		)
		(pin "2"
		)
		(instances
			(project "jetson-orin-baseboard-oculink-expansion"
				(path ""
					(reference "C24")
					(unit 1)
				)
			)
		)
	)
	(symbol
		(lib_id "antmicroResistors0402:R_5k6_0402")
		(at 281.94 130.81 90)
		(unit 1)
		(exclude_from_sim no)
		(in_bom yes)
		(on_board yes)
		(dnp no)
		(property "Reference" "R46"
			(at 283.21 127 90)
			(effects
				(font
					(size 1.27 1.27)
					(thickness 0.15)
				)
				(justify right)
			)
		)
		(property "Value" "R_5k6_0402"
			(at 294.64 110.49 0)
			(effects
				(font
					(size 1.27 1.27)
					(thickness 0.15)
				)
				(justify left bottom)
				(hide yes)
			)
		)
		(property "Footprint" "antmicro-footprints:R_0402_1005Metric"
			(at 297.18 110.49 0)
			(effects
				(font
					(size 1.27 1.27)
					(thickness 0.15)
				)
				(justify left bottom)
				(hide yes)
			)
		)
		(property "Datasheet" "https://www.bourns.com/docs/product-datasheets/cr.pdf"
			(at 299.72 110.49 0)
			(effects
				(font
					(size 1.27 1.27)
					(thickness 0.15)
				)
				(justify left bottom)
				(hide yes)
			)
		)
		(property "Description" "SMD Chip Resistor, 5.6 kohm, ± 1%, 62.5 mW, 0402 [1005 Metric], Thick Film, General Purpose"
			(at 281.94 130.81 0)
			(effects
				(font
					(size 1.27 1.27)
				)
				(hide yes)
			)
		)
		(property "MPN" "CR0402-FX-5601GLF"
			(at 302.26 110.49 0)
			(effects
				(font
					(size 1.27 1.27)
					(thickness 0.15)
				)
				(justify left bottom)
				(hide yes)
			)
		)
		(property "Manufacturer" "Bourns"
			(at 304.8 110.49 0)
			(effects
				(font
					(size 1.27 1.27)
					(thickness 0.15)
				)
				(justify left bottom)
				(hide yes)
			)
		)
		(property "License" "Apache-2.0"
			(at 307.34 110.49 0)
			(effects
				(font
					(size 1.27 1.27)
					(thickness 0.15)
				)
				(justify left bottom)
				(hide yes)
			)
		)
		(property "Author" "Antmicro"
			(at 309.88 110.49 0)
			(effects
				(font
					(size 1.27 1.27)
					(thickness 0.15)
				)
				(justify left bottom)
				(hide yes)
			)
		)
		(property "Val" "5k6"
			(at 283.21 129.54 90)
			(effects
				(font
					(size 1.27 1.27)
					(thickness 0.15)
				)
				(justify right)
			)
		)
		(property "Tolerance" "1%"
			(at 292.1 110.49 0)
			(effects
				(font
					(size 1.27 1.27)
				)
				(justify left bottom)
				(hide yes)
			)
		)
		(pin "1"
		)
		(pin "2"
		)
		(instances
			(project ""
				(path ""
					(reference "R46")
					(unit 1)
				)
			)
		)
	)
	(symbol
		(lib_id "antmicropower:GND")
		(at 163.83 172.72 0)
		(mirror y)
		(unit 1)
		(exclude_from_sim no)
		(in_bom yes)
		(on_board yes)
		(dnp no)
		(property "Reference" "#PWR030"
			(at 154.94 175.26 0)
			(effects
				(font
					(size 1.27 1.27)
					(thickness 0.15)
				)
				(justify left bottom)
				(hide yes)
			)
		)
		(property "Value" "GND"
			(at 163.83 176.53 0)
			(effects
				(font
					(size 1.27 1.27)
					(thickness 0.15)
				)
			)
		)
		(property "Footprint" ""
			(at 154.94 180.34 0)
			(effects
				(font
					(size 1.27 1.27)
					(thickness 0.15)
				)
				(justify left bottom)
				(hide yes)
			)
		)
		(property "Datasheet" ""
			(at 154.94 185.42 0)
			(effects
				(font
					(size 1.27 1.27)
					(thickness 0.15)
				)
				(justify left bottom)
				(hide yes)
			)
		)
		(property "Description" ""
			(at 163.83 172.72 0)
			(effects
				(font
					(size 1.27 1.27)
				)
				(hide yes)
			)
		)
		(property "Author" "Antmicro"
			(at 154.94 180.34 0)
			(effects
				(font
					(size 1.27 1.27)
					(thickness 0.15)
				)
				(justify left bottom)
				(hide yes)
			)
		)
		(property "License" "Apache-2.0"
			(at 154.94 182.88 0)
			(effects
				(font
					(size 1.27 1.27)
					(thickness 0.15)
				)
				(justify left bottom)
				(hide yes)
			)
		)
		(pin "1"
		)
		(instances
			(project "jetson-orin-baseboard-oculink-expansion"
				(path ""
					(reference "#PWR030")
					(unit 1)
				)
			)
		)
	)
	(symbol
		(lib_id "antmicropower:GND")
		(at 386.08 203.2 0)
		(unit 1)
		(exclude_from_sim no)
		(in_bom yes)
		(on_board yes)
		(dnp no)
		(fields_autoplaced yes)
		(property "Reference" "#PWR018"
			(at 386.08 209.55 0)
			(effects
				(font
					(size 1.27 1.27)
				)
				(justify left bottom)
				(hide yes)
			)
		)
		(property "Value" "GND"
			(at 386.08 207.01 0)
			(effects
				(font
					(size 1.27 1.27)
					(thickness 0.15)
				)
			)
		)
		(property "Footprint" ""
			(at 394.97 210.82 0)
			(effects
				(font
					(size 1.27 1.27)
					(thickness 0.15)
				)
				(justify left bottom)
				(hide yes)
			)
		)
		(property "Datasheet" ""
			(at 394.97 215.9 0)
			(effects
				(font
					(size 1.27 1.27)
					(thickness 0.15)
				)
				(justify left bottom)
				(hide yes)
			)
		)
		(property "Description" ""
			(at 386.08 203.2 0)
			(effects
				(font
					(size 1.27 1.27)
				)
				(hide yes)
			)
		)
		(property "Author" "Antmicro"
			(at 394.97 210.82 0)
			(effects
				(font
					(size 1.27 1.27)
					(thickness 0.15)
				)
				(justify left bottom)
				(hide yes)
			)
		)
		(property "License" "Apache-2.0"
			(at 394.97 213.36 0)
			(effects
				(font
					(size 1.27 1.27)
					(thickness 0.15)
				)
				(justify left bottom)
				(hide yes)
			)
		)
		(pin "1"
		)
		(instances
			(project "jetson-orin-baseboard-oculink-expansion"
				(path ""
					(reference "#PWR018")
					(unit 1)
				)
			)
		)
	)
	(symbol
		(lib_id "antmicroCapacitors0402:C_100n_0402")
		(at 156.21 34.29 90)
		(unit 1)
		(exclude_from_sim no)
		(in_bom yes)
		(on_board yes)
		(dnp no)
		(fields_autoplaced yes)
		(property "Reference" "C19"
			(at 158.75 30.4736 90)
			(effects
				(font
					(size 1.27 1.27)
					(thickness 0.15)
				)
				(justify right)
			)
		)
		(property "Value" "C_100n_0402"
			(at 166.37 13.97 0)
			(effects
				(font
					(size 1.27 1.27)
					(thickness 0.15)
				)
				(justify left bottom)
				(hide yes)
			)
		)
		(property "Footprint" "antmicro-footprints:C_0402_1005Metric"
			(at 168.91 13.97 0)
			(effects
				(font
					(size 1.27 1.27)
					(thickness 0.15)
				)
				(justify left bottom)
				(hide yes)
			)
		)
		(property "Datasheet" "https://www.murata.com/products/productdetail?partno=GRM155R61H104KE14%23"
			(at 171.45 13.97 0)
			(effects
				(font
					(size 1.27 1.27)
					(thickness 0.15)
				)
				(justify left bottom)
				(hide yes)
			)
		)
		(property "Description" "SMD Multilayer Ceramic Capacitor, 0.1 µF, 50 V, 0402 [1005 Metric], ± 10%, X5R, GRM Series"
			(at 156.21 34.29 0)
			(effects
				(font
					(size 1.27 1.27)
				)
				(hide yes)
			)
		)
		(property "MPN" "GRM155R61H104KE14D"
			(at 173.99 13.97 0)
			(effects
				(font
					(size 1.27 1.27)
					(thickness 0.15)
				)
				(justify left bottom)
				(hide yes)
			)
		)
		(property "Manufacturer" "Murata"
			(at 176.53 13.97 0)
			(effects
				(font
					(size 1.27 1.27)
					(thickness 0.15)
				)
				(justify left bottom)
				(hide yes)
			)
		)
		(property "License" "Apache-2.0"
			(at 179.07 13.97 0)
			(effects
				(font
					(size 1.27 1.27)
					(thickness 0.15)
				)
				(justify left bottom)
				(hide yes)
			)
		)
		(property "Author" "Antmicro"
			(at 181.61 13.97 0)
			(effects
				(font
					(size 1.27 1.27)
					(thickness 0.15)
				)
				(justify left bottom)
				(hide yes)
			)
		)
		(property "Val" "100n"
			(at 158.75 33.0136 90)
			(effects
				(font
					(size 1.27 1.27)
					(thickness 0.15)
				)
				(justify right)
			)
		)
		(property "Voltage" "50V"
			(at 184.15 13.97 0)
			(effects
				(font
					(size 1.27 1.27)
				)
				(justify left bottom)
				(hide yes)
			)
		)
		(property "Dielectric" "X5R"
			(at 186.69 13.97 0)
			(effects
				(font
					(size 1.27 1.27)
				)
				(justify left bottom)
				(hide yes)
			)
		)
		(property "Public" "False"
			(at 189.23 13.97 0)
			(effects
				(font
					(size 1.27 1.27)
				)
				(justify left bottom)
				(hide yes)
			)
		)
		(pin "1"
		)
		(pin "2"
		)
		(instances
			(project "jetson-orin-baseboard-oculink-expansion"
				(path ""
					(reference "C19")
					(unit 1)
				)
			)
		)
	)
	(symbol
		(lib_id "antmicroResistors0402:R_0R_0402")
		(at 246.38 229.87 90)
		(mirror x)
		(unit 1)
		(exclude_from_sim no)
		(in_bom yes)
		(on_board yes)
		(dnp yes)
		(property "Reference" "R39"
			(at 250.19 234.188 0)
			(effects
				(font
					(size 1.27 1.27)
					(thickness 0.15)
				)
				(justify right)
			)
		)
		(property "Value" "R_0R_0402"
			(at 259.08 250.19 0)
			(effects
				(font
					(size 1.27 1.27)
					(thickness 0.15)
				)
				(justify left bottom)
				(hide yes)
			)
		)
		(property "Footprint" "antmicro-footprints:R_0402_1005Metric"
			(at 261.62 250.19 0)
			(effects
				(font
					(size 1.27 1.27)
					(thickness 0.15)
				)
				(justify left bottom)
				(hide yes)
			)
		)
		(property "Datasheet" "https://industrial.panasonic.com/cdbs/www-data/pdf/RDA0000/AOA0000C301.pdf"
			(at 264.16 250.19 0)
			(effects
				(font
					(size 1.27 1.27)
					(thickness 0.15)
				)
				(justify left bottom)
				(hide yes)
			)
		)
		(property "Description" "SMD Chip Resistor, Jumper, 0 ohm, 100 mW, 0402 [1005 Metric], Thick Film, General Purpose"
			(at 246.38 229.87 0)
			(effects
				(font
					(size 1.27 1.27)
				)
				(hide yes)
			)
		)
		(property "MPN" "ERJ2GE0R00X"
			(at 266.7 250.19 0)
			(effects
				(font
					(size 1.27 1.27)
					(thickness 0.15)
				)
				(justify left bottom)
				(hide yes)
			)
		)
		(property "Manufacturer" "Panasonic"
			(at 269.24 250.19 0)
			(effects
				(font
					(size 1.27 1.27)
					(thickness 0.15)
				)
				(justify left bottom)
				(hide yes)
			)
		)
		(property "License" "Apache-2.0"
			(at 271.78 250.19 0)
			(effects
				(font
					(size 1.27 1.27)
					(thickness 0.15)
				)
				(justify left bottom)
				(hide yes)
			)
		)
		(property "Author" "Antmicro"
			(at 274.32 250.19 0)
			(effects
				(font
					(size 1.27 1.27)
					(thickness 0.15)
				)
				(justify left bottom)
				(hide yes)
			)
		)
		(property "Val" "0R"
			(at 248.412 234.188 0)
			(effects
				(font
					(size 1.27 1.27)
					(thickness 0.15)
				)
				(justify right)
			)
		)
		(property "Tolerance" "~"
			(at 256.54 250.19 0)
			(effects
				(font
					(size 1.27 1.27)
				)
				(justify left bottom)
				(hide yes)
			)
		)
		(property "Current" "1A"
			(at 276.86 250.19 0)
			(effects
				(font
					(size 1.27 1.27)
					(thickness 0.15)
				)
				(justify left bottom)
				(hide yes)
			)
		)
		(property "Public" "False"
			(at 276.86 250.19 0)
			(effects
				(font
					(size 1.27 1.27)
				)
				(justify left bottom)
				(hide yes)
			)
		)
		(pin "1"
		)
		(pin "2"
		)
		(instances
			(project "jetson-orin-baseboard-oculink-expansion"
				(path ""
					(reference "R39")
					(unit 1)
				)
			)
		)
	)
	(symbol
		(lib_id "antmicroResistors0402:R_0R_0402")
		(at 173.99 91.44 270)
		(unit 1)
		(exclude_from_sim no)
		(in_bom yes)
		(on_board yes)
		(dnp yes)
		(property "Reference" "R38"
			(at 170.18 95.758 0)
			(effects
				(font
					(size 1.27 1.27)
					(thickness 0.15)
				)
				(justify right)
			)
		)
		(property "Value" "R_0R_0402"
			(at 161.29 111.76 0)
			(effects
				(font
					(size 1.27 1.27)
					(thickness 0.15)
				)
				(justify left bottom)
				(hide yes)
			)
		)
		(property "Footprint" "antmicro-footprints:R_0402_1005Metric"
			(at 158.75 111.76 0)
			(effects
				(font
					(size 1.27 1.27)
					(thickness 0.15)
				)
				(justify left bottom)
				(hide yes)
			)
		)
		(property "Datasheet" "https://industrial.panasonic.com/cdbs/www-data/pdf/RDA0000/AOA0000C301.pdf"
			(at 156.21 111.76 0)
			(effects
				(font
					(size 1.27 1.27)
					(thickness 0.15)
				)
				(justify left bottom)
				(hide yes)
			)
		)
		(property "Description" "SMD Chip Resistor, Jumper, 0 ohm, 100 mW, 0402 [1005 Metric], Thick Film, General Purpose"
			(at 173.99 91.44 0)
			(effects
				(font
					(size 1.27 1.27)
				)
				(hide yes)
			)
		)
		(property "MPN" "ERJ2GE0R00X"
			(at 153.67 111.76 0)
			(effects
				(font
					(size 1.27 1.27)
					(thickness 0.15)
				)
				(justify left bottom)
				(hide yes)
			)
		)
		(property "Manufacturer" "Panasonic"
			(at 151.13 111.76 0)
			(effects
				(font
					(size 1.27 1.27)
					(thickness 0.15)
				)
				(justify left bottom)
				(hide yes)
			)
		)
		(property "License" "Apache-2.0"
			(at 148.59 111.76 0)
			(effects
				(font
					(size 1.27 1.27)
					(thickness 0.15)
				)
				(justify left bottom)
				(hide yes)
			)
		)
		(property "Author" "Antmicro"
			(at 146.05 111.76 0)
			(effects
				(font
					(size 1.27 1.27)
					(thickness 0.15)
				)
				(justify left bottom)
				(hide yes)
			)
		)
		(property "Val" "0R"
			(at 171.958 95.758 0)
			(effects
				(font
					(size 1.27 1.27)
					(thickness 0.15)
				)
				(justify right)
			)
		)
		(property "Tolerance" "~"
			(at 163.83 111.76 0)
			(effects
				(font
					(size 1.27 1.27)
				)
				(justify left bottom)
				(hide yes)
			)
		)
		(property "Current" "1A"
			(at 143.51 111.76 0)
			(effects
				(font
					(size 1.27 1.27)
					(thickness 0.15)
				)
				(justify left bottom)
				(hide yes)
			)
		)
		(property "Public" "False"
			(at 143.51 111.76 0)
			(effects
				(font
					(size 1.27 1.27)
				)
				(justify left bottom)
				(hide yes)
			)
		)
		(pin "1"
		)
		(pin "2"
		)
		(instances
			(project "jetson-orin-baseboard-oculink-expansion"
				(path ""
					(reference "R38")
					(unit 1)
				)
			)
		)
	)
	(symbol
		(lib_id "antmicropower:+3V3")
		(at 243.84 209.55 0)
		(unit 1)
		(exclude_from_sim no)
		(in_bom yes)
		(on_board yes)
		(dnp no)
		(property "Reference" "#PWR039"
			(at 259.08 209.55 0)
			(effects
				(font
					(size 1.27 1.27)
					(thickness 0.15)
				)
				(justify left bottom)
				(hide yes)
			)
		)
		(property "Value" "+3V3"
			(at 243.84 204.47 0)
			(effects
				(font
					(size 1.27 1.27)
					(thickness 0.15)
				)
			)
		)
		(property "Footprint" ""
			(at 259.08 217.17 0)
			(effects
				(font
					(size 1.27 1.27)
					(thickness 0.15)
				)
				(justify left bottom)
				(hide yes)
			)
		)
		(property "Datasheet" ""
			(at 259.08 219.71 0)
			(effects
				(font
					(size 1.27 1.27)
					(thickness 0.15)
				)
				(justify left bottom)
				(hide yes)
			)
		)
		(property "Description" ""
			(at 243.84 209.55 0)
			(effects
				(font
					(size 1.27 1.27)
				)
				(hide yes)
			)
		)
		(property "Author" "Antmicro"
			(at 259.08 212.09 0)
			(effects
				(font
					(size 1.27 1.27)
					(thickness 0.15)
				)
				(justify left bottom)
				(hide yes)
			)
		)
		(property "License" "Apache-2.0"
			(at 259.08 214.63 0)
			(effects
				(font
					(size 1.27 1.27)
					(thickness 0.15)
				)
				(justify left bottom)
				(hide yes)
			)
		)
		(pin "1"
		)
		(instances
			(project "jetson-orin-baseboard-oculink-expansion"
				(path ""
					(reference "#PWR039")
					(unit 1)
				)
			)
		)
	)
	(symbol
		(lib_id "antmicroResistors0402:R_1k_0402")
		(at 265.43 240.03 90)
		(mirror x)
		(unit 1)
		(exclude_from_sim no)
		(in_bom yes)
		(on_board yes)
		(dnp no)
		(property "Reference" "R8"
			(at 265.43 236.22 0)
			(effects
				(font
					(size 1.27 1.27)
					(thickness 0.15)
				)
				(justify right)
			)
		)
		(property "Value" "R_1k_0402"
			(at 278.13 260.35 0)
			(effects
				(font
					(size 1.27 1.27)
					(thickness 0.15)
				)
				(justify left bottom)
				(hide yes)
			)
		)
		(property "Footprint" "antmicro-footprints:R_0402_1005Metric"
			(at 280.67 260.35 0)
			(effects
				(font
					(size 1.27 1.27)
					(thickness 0.15)
				)
				(justify left bottom)
				(hide yes)
			)
		)
		(property "Datasheet" "https://www.bourns.com/docs/product-datasheets/cr.pdf"
			(at 283.21 260.35 0)
			(effects
				(font
					(size 1.27 1.27)
					(thickness 0.15)
				)
				(justify left bottom)
				(hide yes)
			)
		)
		(property "Description" "SMD Chip Resistor, 1 kohm, ± 1%, 63 mW, 0402 [1005 Metric], Thick Film, General Purpose"
			(at 265.43 240.03 0)
			(effects
				(font
					(size 1.27 1.27)
				)
				(hide yes)
			)
		)
		(property "MPN" "CR0402-FX-1001GLF"
			(at 285.75 260.35 0)
			(effects
				(font
					(size 1.27 1.27)
					(thickness 0.15)
				)
				(justify left bottom)
				(hide yes)
			)
		)
		(property "Manufacturer" "Bourns"
			(at 288.29 260.35 0)
			(effects
				(font
					(size 1.27 1.27)
					(thickness 0.15)
				)
				(justify left bottom)
				(hide yes)
			)
		)
		(property "License" "Apache-2.0"
			(at 290.83 260.35 0)
			(effects
				(font
					(size 1.27 1.27)
					(thickness 0.15)
				)
				(justify left bottom)
				(hide yes)
			)
		)
		(property "Author" "Antmicro"
			(at 293.37 260.35 0)
			(effects
				(font
					(size 1.27 1.27)
					(thickness 0.15)
				)
				(justify left bottom)
				(hide yes)
			)
		)
		(property "Val" "1k"
			(at 264.16 240.03 0)
			(effects
				(font
					(size 1.27 1.27)
					(thickness 0.15)
				)
				(justify right)
			)
		)
		(property "Tolerance" "1%"
			(at 275.59 260.35 0)
			(effects
				(font
					(size 1.27 1.27)
				)
				(justify left bottom)
				(hide yes)
			)
		)
		(property "Public" "False"
			(at 295.91 260.35 0)
			(effects
				(font
					(size 1.27 1.27)
				)
				(justify left bottom)
				(hide yes)
			)
		)
		(pin "1"
		)
		(pin "2"
		)
		(instances
			(project "jetson-orin-baseboard-oculink-expansion"
				(path ""
					(reference "R8")
					(unit 1)
				)
			)
		)
	)
	(symbol
		(lib_id "antmicroTestPoints:TP_1.5mm_SMD")
		(at 304.8 53.34 180)
		(unit 1)
		(exclude_from_sim no)
		(in_bom no)
		(on_board yes)
		(dnp no)
		(property "Reference" "TP2"
			(at 297.18 53.594 0)
			(effects
				(font
					(size 1.27 1.27)
					(thickness 0.15)
				)
				(justify right)
			)
		)
		(property "Value" "TP_1.5mm_SMD"
			(at 289.56 45.72 0)
			(effects
				(font
					(size 1.27 1.27)
					(thickness 0.15)
				)
				(justify left bottom)
				(hide yes)
			)
		)
		(property "Footprint" "antmicro-footprints:TP_SMD_1.5mm"
			(at 289.56 43.18 0)
			(effects
				(font
					(size 1.27 1.27)
					(thickness 0.15)
				)
				(justify left bottom)
				(hide yes)
			)
		)
		(property "Datasheet" ""
			(at 287.02 40.64 0)
			(effects
				(font
					(size 1.27 1.27)
					(thickness 0.15)
				)
				(justify left bottom)
				(hide yes)
			)
		)
		(property "Description" "test point, SMT"
			(at 304.8 53.34 0)
			(effects
				(font
					(size 1.27 1.27)
				)
				(hide yes)
			)
		)
		(property "MPN" ""
			(at 304.8 53.34 0)
			(effects
				(font
					(size 1.27 1.27)
				)
				(hide yes)
			)
		)
		(property "Manufacturer" ""
			(at 304.8 53.34 0)
			(effects
				(font
					(size 1.27 1.27)
				)
				(hide yes)
			)
		)
		(property "Author" "Antmicro"
			(at 289.56 38.1 0)
			(effects
				(font
					(size 1.27 1.27)
					(thickness 0.15)
				)
				(justify left bottom)
				(hide yes)
			)
		)
		(property "License" "Apache-2.0"
			(at 289.56 35.56 0)
			(effects
				(font
					(size 1.27 1.27)
					(thickness 0.15)
				)
				(justify left bottom)
				(hide yes)
			)
		)
		(pin "1"
		)
		(instances
			(project "jetson-orin-baseboard-oculink-expansion"
				(path ""
					(reference "TP2")
					(unit 1)
				)
			)
		)
	)
	(symbol
		(lib_id "antmicroResistors0402:R_0R_0402")
		(at 166.37 80.01 0)
		(unit 1)
		(exclude_from_sim no)
		(in_bom yes)
		(on_board yes)
		(dnp yes)
		(property "Reference" "R44"
			(at 170.942 77.47 0)
			(effects
				(font
					(size 1.27 1.27)
					(thickness 0.15)
				)
				(justify right)
			)
		)
		(property "Value" "R_0R_0402"
			(at 186.69 92.71 0)
			(effects
				(font
					(size 1.27 1.27)
					(thickness 0.15)
				)
				(justify left bottom)
				(hide yes)
			)
		)
		(property "Footprint" "antmicro-footprints:R_0402_1005Metric"
			(at 186.69 95.25 0)
			(effects
				(font
					(size 1.27 1.27)
					(thickness 0.15)
				)
				(justify left bottom)
				(hide yes)
			)
		)
		(property "Datasheet" "https://industrial.panasonic.com/cdbs/www-data/pdf/RDA0000/AOA0000C301.pdf"
			(at 186.69 97.79 0)
			(effects
				(font
					(size 1.27 1.27)
					(thickness 0.15)
				)
				(justify left bottom)
				(hide yes)
			)
		)
		(property "Description" "SMD Chip Resistor, Jumper, 0 ohm, 100 mW, 0402 [1005 Metric], Thick Film, General Purpose"
			(at 166.37 80.01 0)
			(effects
				(font
					(size 1.27 1.27)
				)
				(hide yes)
			)
		)
		(property "MPN" "ERJ2GE0R00X"
			(at 186.69 100.33 0)
			(effects
				(font
					(size 1.27 1.27)
					(thickness 0.15)
				)
				(justify left bottom)
				(hide yes)
			)
		)
		(property "Manufacturer" "Panasonic"
			(at 186.69 102.87 0)
			(effects
				(font
					(size 1.27 1.27)
					(thickness 0.15)
				)
				(justify left bottom)
				(hide yes)
			)
		)
		(property "License" "Apache-2.0"
			(at 186.69 105.41 0)
			(effects
				(font
					(size 1.27 1.27)
					(thickness 0.15)
				)
				(justify left bottom)
				(hide yes)
			)
		)
		(property "Author" "Antmicro"
			(at 186.69 107.95 0)
			(effects
				(font
					(size 1.27 1.27)
					(thickness 0.15)
				)
				(justify left bottom)
				(hide yes)
			)
		)
		(property "Val" "0R"
			(at 169.672 75.692 0)
			(effects
				(font
					(size 1.27 1.27)
					(thickness 0.15)
				)
				(justify right)
			)
		)
		(property "Tolerance" "~"
			(at 186.69 90.17 0)
			(effects
				(font
					(size 1.27 1.27)
				)
				(justify left bottom)
				(hide yes)
			)
		)
		(property "Current" "1A"
			(at 186.69 110.49 0)
			(effects
				(font
					(size 1.27 1.27)
					(thickness 0.15)
				)
				(justify left bottom)
				(hide yes)
			)
		)
		(property "Public" "False"
			(at 186.69 110.49 0)
			(effects
				(font
					(size 1.27 1.27)
				)
				(justify left bottom)
				(hide yes)
			)
		)
		(pin "1"
		)
		(pin "2"
		)
		(instances
			(project "jetson-orin-baseboard-oculink-expansion"
				(path ""
					(reference "R44")
					(unit 1)
				)
			)
		)
	)
	(symbol
		(lib_id "antmicroCapacitors0402:C_10u_0402")
		(at 336.55 163.83 90)
		(unit 1)
		(exclude_from_sim no)
		(in_bom yes)
		(on_board yes)
		(dnp no)
		(fields_autoplaced yes)
		(property "Reference" "C3"
			(at 339.09 160.0136 90)
			(effects
				(font
					(size 1.27 1.27)
					(thickness 0.15)
				)
				(justify right)
			)
		)
		(property "Value" "C_10u_0402"
			(at 346.71 143.51 0)
			(effects
				(font
					(size 1.27 1.27)
					(thickness 0.15)
				)
				(justify left bottom)
				(hide yes)
			)
		)
		(property "Footprint" "antmicro-footprints:C_0402_1005Metric"
			(at 349.25 143.51 0)
			(effects
				(font
					(size 1.27 1.27)
					(thickness 0.15)
				)
				(justify left bottom)
				(hide yes)
			)
		)
		(property "Datasheet" "https://www.yageo.com/en/Chart/Download/pdf/CC0402MRX5R5BB106"
			(at 351.79 143.51 0)
			(effects
				(font
					(size 1.27 1.27)
					(thickness 0.15)
				)
				(justify left bottom)
				(hide yes)
			)
		)
		(property "Description" "SMD Multilayer Ceramic Capacitor, 10 µF, 6.3 V, 0402 [1005 Metric], ± 20%, X5R, CC Series"
			(at 336.55 163.83 0)
			(effects
				(font
					(size 1.27 1.27)
				)
				(hide yes)
			)
		)
		(property "MPN" "CC0402MRX5R5BB106"
			(at 354.33 143.51 0)
			(effects
				(font
					(size 1.27 1.27)
					(thickness 0.15)
				)
				(justify left bottom)
				(hide yes)
			)
		)
		(property "Manufacturer" "YAGEO"
			(at 356.87 143.51 0)
			(effects
				(font
					(size 1.27 1.27)
					(thickness 0.15)
				)
				(justify left bottom)
				(hide yes)
			)
		)
		(property "License" "Apache-2.0"
			(at 359.41 143.51 0)
			(effects
				(font
					(size 1.27 1.27)
					(thickness 0.15)
				)
				(justify left bottom)
				(hide yes)
			)
		)
		(property "Author" "Antmicro"
			(at 361.95 143.51 0)
			(effects
				(font
					(size 1.27 1.27)
					(thickness 0.15)
				)
				(justify left bottom)
				(hide yes)
			)
		)
		(property "Val" "10u"
			(at 339.09 162.5536 90)
			(effects
				(font
					(size 1.27 1.27)
					(thickness 0.15)
				)
				(justify right)
			)
		)
		(property "Voltage" ""
			(at 364.49 143.51 0)
			(effects
				(font
					(size 1.27 1.27)
				)
				(justify left bottom)
				(hide yes)
			)
		)
		(property "Dielectric" ""
			(at 367.03 143.51 0)
			(effects
				(font
					(size 1.27 1.27)
				)
				(justify left bottom)
				(hide yes)
			)
		)
		(pin "1"
		)
		(pin "2"
		)
		(instances
			(project "jetson-orin-baseboard-oculink-expansion"
				(path ""
					(reference "C3")
					(unit 1)
				)
			)
		)
	)
	(symbol
		(lib_id "antmicroCapacitors0402:C_220n_0402")
		(at 247.65 71.12 0)
		(unit 1)
		(exclude_from_sim no)
		(in_bom yes)
		(on_board yes)
		(dnp no)
		(property "Reference" "C14"
			(at 246.38 69.85 0)
			(effects
				(font
					(size 1.27 1.27)
					(thickness 0.15)
				)
			)
		)
		(property "Value" "C_220n_0402"
			(at 267.97 81.28 0)
			(effects
				(font
					(size 1.27 1.27)
					(thickness 0.15)
				)
				(justify left bottom)
				(hide yes)
			)
		)
		(property "Footprint" "antmicro-footprints:C_0402_1005Metric"
			(at 267.97 83.82 0)
			(effects
				(font
					(size 1.27 1.27)
					(thickness 0.15)
				)
				(justify left bottom)
				(hide yes)
			)
		)
		(property "Datasheet" "https://www.yageo.com/en/Chart/Download/pdf/CC0402KRX5R6BB224"
			(at 267.97 86.36 0)
			(effects
				(font
					(size 1.27 1.27)
					(thickness 0.15)
				)
				(justify left bottom)
				(hide yes)
			)
		)
		(property "Description" "SMD Multilayer Ceramic Capacitor, 0.22 µF, 10 V, 0402 [1005 Metric], ± 10%, X5R, CC Series"
			(at 247.65 71.12 0)
			(effects
				(font
					(size 1.27 1.27)
				)
				(hide yes)
			)
		)
		(property "MPN" "CC0402KRX5R6BB224"
			(at 267.97 88.9 0)
			(effects
				(font
					(size 1.27 1.27)
					(thickness 0.15)
				)
				(justify left bottom)
				(hide yes)
			)
		)
		(property "Manufacturer" "YAGEO"
			(at 267.97 91.44 0)
			(effects
				(font
					(size 1.27 1.27)
					(thickness 0.15)
				)
				(justify left bottom)
				(hide yes)
			)
		)
		(property "License" "Apache-2.0"
			(at 267.97 93.98 0)
			(effects
				(font
					(size 1.27 1.27)
					(thickness 0.15)
				)
				(justify left bottom)
				(hide yes)
			)
		)
		(property "Author" "Antmicro"
			(at 267.97 96.52 0)
			(effects
				(font
					(size 1.27 1.27)
					(thickness 0.15)
				)
				(justify left bottom)
				(hide yes)
			)
		)
		(property "Val" "220n"
			(at 254 69.85 0)
			(effects
				(font
					(size 1.27 1.27)
					(thickness 0.15)
				)
			)
		)
		(property "Voltage" ""
			(at 267.97 99.06 0)
			(effects
				(font
					(size 1.27 1.27)
				)
				(justify left bottom)
				(hide yes)
			)
		)
		(property "Dielectric" ""
			(at 267.97 101.6 0)
			(effects
				(font
					(size 1.27 1.27)
				)
				(justify left bottom)
				(hide yes)
			)
		)
		(property "Public" "False"
			(at 267.97 104.14 0)
			(effects
				(font
					(size 1.27 1.27)
				)
				(justify left bottom)
				(hide yes)
			)
		)
		(pin "1"
		)
		(pin "2"
		)
		(instances
			(project "jetson-orin-baseboard-oculink-expansion"
				(path ""
					(reference "C14")
					(unit 1)
				)
			)
		)
	)
	(symbol
		(lib_id "antmicroResistors0402:R_0R_0402")
		(at 303.53 166.37 0)
		(unit 1)
		(exclude_from_sim no)
		(in_bom yes)
		(on_board yes)
		(dnp no)
		(property "Reference" "R50"
			(at 302.006 165.354 0)
			(effects
				(font
					(size 1.27 1.27)
					(thickness 0.15)
				)
			)
		)
		(property "Value" "R_0R_0402"
			(at 323.85 179.07 0)
			(effects
				(font
					(size 1.27 1.27)
					(thickness 0.15)
				)
				(justify left bottom)
				(hide yes)
			)
		)
		(property "Footprint" "antmicro-footprints:R_0402_1005Metric"
			(at 323.85 181.61 0)
			(effects
				(font
					(size 1.27 1.27)
					(thickness 0.15)
				)
				(justify left bottom)
				(hide yes)
			)
		)
		(property "Datasheet" "https://industrial.panasonic.com/cdbs/www-data/pdf/RDA0000/AOA0000C301.pdf"
			(at 323.85 184.15 0)
			(effects
				(font
					(size 1.27 1.27)
					(thickness 0.15)
				)
				(justify left bottom)
				(hide yes)
			)
		)
		(property "Description" "SMD Chip Resistor, Jumper, 0 ohm, 100 mW, 0402 [1005 Metric], Thick Film, General Purpose"
			(at 303.53 166.37 0)
			(effects
				(font
					(size 1.27 1.27)
				)
				(hide yes)
			)
		)
		(property "MPN" "ERJ2GE0R00X"
			(at 323.85 186.69 0)
			(effects
				(font
					(size 1.27 1.27)
					(thickness 0.15)
				)
				(justify left bottom)
				(hide yes)
			)
		)
		(property "Manufacturer" "Panasonic"
			(at 323.85 189.23 0)
			(effects
				(font
					(size 1.27 1.27)
					(thickness 0.15)
				)
				(justify left bottom)
				(hide yes)
			)
		)
		(property "License" "Apache-2.0"
			(at 323.85 191.77 0)
			(effects
				(font
					(size 1.27 1.27)
					(thickness 0.15)
				)
				(justify left bottom)
				(hide yes)
			)
		)
		(property "Author" "Antmicro"
			(at 323.85 194.31 0)
			(effects
				(font
					(size 1.27 1.27)
					(thickness 0.15)
				)
				(justify left bottom)
				(hide yes)
			)
		)
		(property "Val" "0R"
			(at 309.626 165.354 0)
			(effects
				(font
					(size 1.27 1.27)
					(thickness 0.15)
				)
			)
		)
		(property "Tolerance" "~"
			(at 323.85 176.53 0)
			(effects
				(font
					(size 1.27 1.27)
				)
				(justify left bottom)
				(hide yes)
			)
		)
		(property "Current" "1A"
			(at 323.85 196.85 0)
			(effects
				(font
					(size 1.27 1.27)
					(thickness 0.15)
				)
				(justify left bottom)
				(hide yes)
			)
		)
		(pin "1"
		)
		(pin "2"
		)
		(instances
			(project "jetson-orin-baseboard-oculink-expansion"
				(path ""
					(reference "R50")
					(unit 1)
				)
			)
		)
	)
	(symbol
		(lib_id "antmicropower:GND")
		(at 165.1 34.29 0)
		(unit 1)
		(exclude_from_sim no)
		(in_bom yes)
		(on_board yes)
		(dnp no)
		(property "Reference" "#PWR044"
			(at 173.99 36.83 0)
			(effects
				(font
					(size 1.27 1.27)
					(thickness 0.15)
				)
				(justify left bottom)
				(hide yes)
			)
		)
		(property "Value" "GND"
			(at 165.1 38.1 0)
			(effects
				(font
					(size 1.27 1.27)
					(thickness 0.15)
				)
			)
		)
		(property "Footprint" ""
			(at 173.99 41.91 0)
			(effects
				(font
					(size 1.27 1.27)
					(thickness 0.15)
				)
				(justify left bottom)
				(hide yes)
			)
		)
		(property "Datasheet" ""
			(at 173.99 46.99 0)
			(effects
				(font
					(size 1.27 1.27)
					(thickness 0.15)
				)
				(justify left bottom)
				(hide yes)
			)
		)
		(property "Description" ""
			(at 165.1 34.29 0)
			(effects
				(font
					(size 1.27 1.27)
				)
				(hide yes)
			)
		)
		(property "Author" "Antmicro"
			(at 173.99 41.91 0)
			(effects
				(font
					(size 1.27 1.27)
					(thickness 0.15)
				)
				(justify left bottom)
				(hide yes)
			)
		)
		(property "License" "Apache-2.0"
			(at 173.99 44.45 0)
			(effects
				(font
					(size 1.27 1.27)
					(thickness 0.15)
				)
				(justify left bottom)
				(hide yes)
			)
		)
		(pin "1"
		)
		(instances
			(project "jetson-orin-baseboard-oculink-expansion"
				(path ""
					(reference "#PWR044")
					(unit 1)
				)
			)
		)
	)
	(symbol
		(lib_id "antmicroCapacitors0402:C_10u_0402")
		(at 345.44 163.83 90)
		(unit 1)
		(exclude_from_sim no)
		(in_bom yes)
		(on_board yes)
		(dnp no)
		(fields_autoplaced yes)
		(property "Reference" "C1"
			(at 347.98 160.0136 90)
			(effects
				(font
					(size 1.27 1.27)
					(thickness 0.15)
				)
				(justify right)
			)
		)
		(property "Value" "C_10u_0402"
			(at 355.6 143.51 0)
			(effects
				(font
					(size 1.27 1.27)
					(thickness 0.15)
				)
				(justify left bottom)
				(hide yes)
			)
		)
		(property "Footprint" "antmicro-footprints:C_0402_1005Metric"
			(at 358.14 143.51 0)
			(effects
				(font
					(size 1.27 1.27)
					(thickness 0.15)
				)
				(justify left bottom)
				(hide yes)
			)
		)
		(property "Datasheet" "https://www.yageo.com/en/Chart/Download/pdf/CC0402MRX5R5BB106"
			(at 360.68 143.51 0)
			(effects
				(font
					(size 1.27 1.27)
					(thickness 0.15)
				)
				(justify left bottom)
				(hide yes)
			)
		)
		(property "Description" "SMD Multilayer Ceramic Capacitor, 10 µF, 6.3 V, 0402 [1005 Metric], ± 20%, X5R, CC Series"
			(at 345.44 163.83 0)
			(effects
				(font
					(size 1.27 1.27)
				)
				(hide yes)
			)
		)
		(property "MPN" "CC0402MRX5R5BB106"
			(at 363.22 143.51 0)
			(effects
				(font
					(size 1.27 1.27)
					(thickness 0.15)
				)
				(justify left bottom)
				(hide yes)
			)
		)
		(property "Manufacturer" "YAGEO"
			(at 365.76 143.51 0)
			(effects
				(font
					(size 1.27 1.27)
					(thickness 0.15)
				)
				(justify left bottom)
				(hide yes)
			)
		)
		(property "License" "Apache-2.0"
			(at 368.3 143.51 0)
			(effects
				(font
					(size 1.27 1.27)
					(thickness 0.15)
				)
				(justify left bottom)
				(hide yes)
			)
		)
		(property "Author" "Antmicro"
			(at 370.84 143.51 0)
			(effects
				(font
					(size 1.27 1.27)
					(thickness 0.15)
				)
				(justify left bottom)
				(hide yes)
			)
		)
		(property "Val" "10u"
			(at 347.98 162.5536 90)
			(effects
				(font
					(size 1.27 1.27)
					(thickness 0.15)
				)
				(justify right)
			)
		)
		(property "Voltage" ""
			(at 373.38 143.51 0)
			(effects
				(font
					(size 1.27 1.27)
				)
				(justify left bottom)
				(hide yes)
			)
		)
		(property "Dielectric" ""
			(at 375.92 143.51 0)
			(effects
				(font
					(size 1.27 1.27)
				)
				(justify left bottom)
				(hide yes)
			)
		)
		(pin "1"
		)
		(pin "2"
		)
		(instances
			(project ""
				(path ""
					(reference "C1")
					(unit 1)
				)
			)
		)
	)
	(symbol
		(lib_id "antmicroResistors0402:R_1k_0402")
		(at 270.51 240.03 90)
		(mirror x)
		(unit 1)
		(exclude_from_sim no)
		(in_bom yes)
		(on_board yes)
		(dnp yes)
		(property "Reference" "R4"
			(at 270.51 236.22 0)
			(effects
				(font
					(size 1.27 1.27)
					(thickness 0.15)
				)
				(justify right)
			)
		)
		(property "Value" "R_1k_0402"
			(at 283.21 260.35 0)
			(effects
				(font
					(size 1.27 1.27)
					(thickness 0.15)
				)
				(justify left bottom)
				(hide yes)
			)
		)
		(property "Footprint" "antmicro-footprints:R_0402_1005Metric"
			(at 285.75 260.35 0)
			(effects
				(font
					(size 1.27 1.27)
					(thickness 0.15)
				)
				(justify left bottom)
				(hide yes)
			)
		)
		(property "Datasheet" "https://www.bourns.com/docs/product-datasheets/cr.pdf"
			(at 288.29 260.35 0)
			(effects
				(font
					(size 1.27 1.27)
					(thickness 0.15)
				)
				(justify left bottom)
				(hide yes)
			)
		)
		(property "Description" "SMD Chip Resistor, 1 kohm, ± 1%, 63 mW, 0402 [1005 Metric], Thick Film, General Purpose"
			(at 270.51 240.03 0)
			(effects
				(font
					(size 1.27 1.27)
				)
				(hide yes)
			)
		)
		(property "MPN" "CR0402-FX-1001GLF"
			(at 290.83 260.35 0)
			(effects
				(font
					(size 1.27 1.27)
					(thickness 0.15)
				)
				(justify left bottom)
				(hide yes)
			)
		)
		(property "Manufacturer" "Bourns"
			(at 293.37 260.35 0)
			(effects
				(font
					(size 1.27 1.27)
					(thickness 0.15)
				)
				(justify left bottom)
				(hide yes)
			)
		)
		(property "License" "Apache-2.0"
			(at 295.91 260.35 0)
			(effects
				(font
					(size 1.27 1.27)
					(thickness 0.15)
				)
				(justify left bottom)
				(hide yes)
			)
		)
		(property "Author" "Antmicro"
			(at 298.45 260.35 0)
			(effects
				(font
					(size 1.27 1.27)
					(thickness 0.15)
				)
				(justify left bottom)
				(hide yes)
			)
		)
		(property "Val" "1k"
			(at 269.24 240.03 0)
			(effects
				(font
					(size 1.27 1.27)
					(thickness 0.15)
				)
				(justify right)
			)
		)
		(property "Tolerance" "1%"
			(at 280.67 260.35 0)
			(effects
				(font
					(size 1.27 1.27)
				)
				(justify left bottom)
				(hide yes)
			)
		)
		(property "Public" "False"
			(at 300.99 260.35 0)
			(effects
				(font
					(size 1.27 1.27)
				)
				(justify left bottom)
				(hide yes)
			)
		)
		(pin "1"
		)
		(pin "2"
		)
		(instances
			(project "jetson-orin-baseboard-oculink-expansion"
				(path ""
					(reference "R4")
					(unit 1)
				)
			)
		)
	)
	(symbol
		(lib_id "antmicropower:GND")
		(at 344.17 227.33 0)
		(mirror y)
		(unit 1)
		(exclude_from_sim no)
		(in_bom yes)
		(on_board yes)
		(dnp no)
		(fields_autoplaced yes)
		(property "Reference" "#PWR020"
			(at 344.17 233.68 0)
			(effects
				(font
					(size 1.27 1.27)
				)
				(justify left bottom)
				(hide yes)
			)
		)
		(property "Value" "GND"
			(at 344.17 231.14 0)
			(effects
				(font
					(size 1.27 1.27)
					(thickness 0.15)
				)
			)
		)
		(property "Footprint" ""
			(at 335.28 234.95 0)
			(effects
				(font
					(size 1.27 1.27)
					(thickness 0.15)
				)
				(justify left bottom)
				(hide yes)
			)
		)
		(property "Datasheet" ""
			(at 335.28 240.03 0)
			(effects
				(font
					(size 1.27 1.27)
					(thickness 0.15)
				)
				(justify left bottom)
				(hide yes)
			)
		)
		(property "Description" ""
			(at 344.17 227.33 0)
			(effects
				(font
					(size 1.27 1.27)
				)
				(hide yes)
			)
		)
		(property "Author" "Antmicro"
			(at 335.28 234.95 0)
			(effects
				(font
					(size 1.27 1.27)
					(thickness 0.15)
				)
				(justify left bottom)
				(hide yes)
			)
		)
		(property "License" "Apache-2.0"
			(at 335.28 237.49 0)
			(effects
				(font
					(size 1.27 1.27)
					(thickness 0.15)
				)
				(justify left bottom)
				(hide yes)
			)
		)
		(pin "1"
		)
		(instances
			(project "jetson-orin-baseboard-oculink-expansion"
				(path ""
					(reference "#PWR020")
					(unit 1)
				)
			)
		)
	)
	(symbol
		(lib_id "antmicropower:+1V8")
		(at 44.45 120.65 0)
		(unit 1)
		(exclude_from_sim no)
		(in_bom yes)
		(on_board yes)
		(dnp no)
		(property "Reference" "#PWR013"
			(at 59.69 123.19 0)
			(effects
				(font
					(size 1.27 1.27)
					(thickness 0.15)
				)
				(justify left bottom)
				(hide yes)
			)
		)
		(property "Value" "+1V8"
			(at 44.704 116.84 0)
			(effects
				(font
					(size 1.27 1.27)
					(thickness 0.15)
				)
			)
		)
		(property "Footprint" ""
			(at 59.69 128.27 0)
			(effects
				(font
					(size 1.27 1.27)
					(thickness 0.15)
				)
				(justify left bottom)
				(hide yes)
			)
		)
		(property "Datasheet" ""
			(at 59.69 130.81 0)
			(effects
				(font
					(size 1.27 1.27)
					(thickness 0.15)
				)
				(justify left bottom)
				(hide yes)
			)
		)
		(property "Description" ""
			(at 44.45 120.65 0)
			(effects
				(font
					(size 1.27 1.27)
				)
				(hide yes)
			)
		)
		(property "Author" "Antmicro"
			(at 59.69 125.73 0)
			(effects
				(font
					(size 1.27 1.27)
					(thickness 0.15)
				)
				(justify left bottom)
				(hide yes)
			)
		)
		(property "License" "Apache-2.0"
			(at 59.69 128.27 0)
			(effects
				(font
					(size 1.27 1.27)
					(thickness 0.15)
				)
				(justify left bottom)
				(hide yes)
			)
		)
		(pin "1"
		)
		(instances
			(project ""
				(path ""
					(reference "#PWR013")
					(unit 1)
				)
			)
		)
	)
	(symbol
		(lib_id "antmicroResistors0402:R_1k_0402")
		(at 267.97 269.24 270)
		(mirror x)
		(unit 1)
		(exclude_from_sim no)
		(in_bom yes)
		(on_board yes)
		(dnp yes)
		(property "Reference" "R7"
			(at 267.97 273.05 0)
			(effects
				(font
					(size 1.27 1.27)
					(thickness 0.15)
				)
				(justify right)
			)
		)
		(property "Value" "R_1k_0402"
			(at 255.27 248.92 0)
			(effects
				(font
					(size 1.27 1.27)
					(thickness 0.15)
				)
				(justify left bottom)
				(hide yes)
			)
		)
		(property "Footprint" "antmicro-footprints:R_0402_1005Metric"
			(at 252.73 248.92 0)
			(effects
				(font
					(size 1.27 1.27)
					(thickness 0.15)
				)
				(justify left bottom)
				(hide yes)
			)
		)
		(property "Datasheet" "https://www.bourns.com/docs/product-datasheets/cr.pdf"
			(at 250.19 248.92 0)
			(effects
				(font
					(size 1.27 1.27)
					(thickness 0.15)
				)
				(justify left bottom)
				(hide yes)
			)
		)
		(property "Description" "SMD Chip Resistor, 1 kohm, ± 1%, 63 mW, 0402 [1005 Metric], Thick Film, General Purpose"
			(at 267.97 269.24 0)
			(effects
				(font
					(size 1.27 1.27)
				)
				(hide yes)
			)
		)
		(property "MPN" "CR0402-FX-1001GLF"
			(at 247.65 248.92 0)
			(effects
				(font
					(size 1.27 1.27)
					(thickness 0.15)
				)
				(justify left bottom)
				(hide yes)
			)
		)
		(property "Manufacturer" "Bourns"
			(at 245.11 248.92 0)
			(effects
				(font
					(size 1.27 1.27)
					(thickness 0.15)
				)
				(justify left bottom)
				(hide yes)
			)
		)
		(property "License" "Apache-2.0"
			(at 242.57 248.92 0)
			(effects
				(font
					(size 1.27 1.27)
					(thickness 0.15)
				)
				(justify left bottom)
				(hide yes)
			)
		)
		(property "Author" "Antmicro"
			(at 240.03 248.92 0)
			(effects
				(font
					(size 1.27 1.27)
					(thickness 0.15)
				)
				(justify left bottom)
				(hide yes)
			)
		)
		(property "Val" "1k"
			(at 269.24 269.24 0)
			(effects
				(font
					(size 1.27 1.27)
					(thickness 0.15)
				)
				(justify right)
			)
		)
		(property "Tolerance" "1%"
			(at 257.81 248.92 0)
			(effects
				(font
					(size 1.27 1.27)
				)
				(justify left bottom)
				(hide yes)
			)
		)
		(property "Public" "False"
			(at 237.49 248.92 0)
			(effects
				(font
					(size 1.27 1.27)
				)
				(justify left bottom)
				(hide yes)
			)
		)
		(pin "1"
		)
		(pin "2"
		)
		(instances
			(project "jetson-orin-baseboard-oculink-expansion"
				(path ""
					(reference "R7")
					(unit 1)
				)
			)
		)
	)
	(symbol
		(lib_id "antmicropower:+3.3V")
		(at 313.69 120.65 0)
		(unit 1)
		(exclude_from_sim no)
		(in_bom yes)
		(on_board yes)
		(dnp no)
		(property "Reference" "#PWR062"
			(at 313.69 124.46 0)
			(effects
				(font
					(size 1.27 1.27)
				)
				(hide yes)
			)
		)
		(property "Value" "+3V3_OCU"
			(at 313.69 115.57 0)
			(effects
				(font
					(size 1.27 1.27)
				)
			)
		)
		(property "Footprint" ""
			(at 313.69 120.65 0)
			(effects
				(font
					(size 1.27 1.27)
				)
				(hide yes)
			)
		)
		(property "Datasheet" ""
			(at 313.69 120.65 0)
			(effects
				(font
					(size 1.27 1.27)
				)
				(hide yes)
			)
		)
		(property "Description" ""
			(at 313.69 120.65 0)
			(effects
				(font
					(size 1.27 1.27)
				)
				(hide yes)
			)
		)
		(pin "1"
		)
		(instances
			(project "jetson-orin-baseboard-oculink-expansion"
				(path ""
					(reference "#PWR062")
					(unit 1)
				)
			)
		)
	)
	(symbol
		(lib_id "antmicroCapacitors0402:C_10u_0402")
		(at 367.03 163.83 90)
		(unit 1)
		(exclude_from_sim no)
		(in_bom yes)
		(on_board yes)
		(dnp no)
		(fields_autoplaced yes)
		(property "Reference" "C4"
			(at 369.57 160.0136 90)
			(effects
				(font
					(size 1.27 1.27)
					(thickness 0.15)
				)
				(justify right)
			)
		)
		(property "Value" "C_10u_0402"
			(at 377.19 143.51 0)
			(effects
				(font
					(size 1.27 1.27)
					(thickness 0.15)
				)
				(justify left bottom)
				(hide yes)
			)
		)
		(property "Footprint" "antmicro-footprints:C_0402_1005Metric"
			(at 379.73 143.51 0)
			(effects
				(font
					(size 1.27 1.27)
					(thickness 0.15)
				)
				(justify left bottom)
				(hide yes)
			)
		)
		(property "Datasheet" "https://www.yageo.com/en/Chart/Download/pdf/CC0402MRX5R5BB106"
			(at 382.27 143.51 0)
			(effects
				(font
					(size 1.27 1.27)
					(thickness 0.15)
				)
				(justify left bottom)
				(hide yes)
			)
		)
		(property "Description" "SMD Multilayer Ceramic Capacitor, 10 µF, 6.3 V, 0402 [1005 Metric], ± 20%, X5R, CC Series"
			(at 367.03 163.83 0)
			(effects
				(font
					(size 1.27 1.27)
				)
				(hide yes)
			)
		)
		(property "MPN" "CC0402MRX5R5BB106"
			(at 384.81 143.51 0)
			(effects
				(font
					(size 1.27 1.27)
					(thickness 0.15)
				)
				(justify left bottom)
				(hide yes)
			)
		)
		(property "Manufacturer" "YAGEO"
			(at 387.35 143.51 0)
			(effects
				(font
					(size 1.27 1.27)
					(thickness 0.15)
				)
				(justify left bottom)
				(hide yes)
			)
		)
		(property "License" "Apache-2.0"
			(at 389.89 143.51 0)
			(effects
				(font
					(size 1.27 1.27)
					(thickness 0.15)
				)
				(justify left bottom)
				(hide yes)
			)
		)
		(property "Author" "Antmicro"
			(at 392.43 143.51 0)
			(effects
				(font
					(size 1.27 1.27)
					(thickness 0.15)
				)
				(justify left bottom)
				(hide yes)
			)
		)
		(property "Val" "10u"
			(at 369.57 162.5536 90)
			(effects
				(font
					(size 1.27 1.27)
					(thickness 0.15)
				)
				(justify right)
			)
		)
		(property "Voltage" ""
			(at 394.97 143.51 0)
			(effects
				(font
					(size 1.27 1.27)
				)
				(justify left bottom)
				(hide yes)
			)
		)
		(property "Dielectric" ""
			(at 397.51 143.51 0)
			(effects
				(font
					(size 1.27 1.27)
				)
				(justify left bottom)
				(hide yes)
			)
		)
		(pin "1"
		)
		(pin "2"
		)
		(instances
			(project "jetson-orin-baseboard-oculink-expansion"
				(path ""
					(reference "C4")
					(unit 1)
				)
			)
		)
	)
	(symbol
		(lib_id "antmicroMechanicalParts:MP_Pad5.4mm_Drill2.7mm")
		(at 340.36 224.79 180)
		(unit 1)
		(exclude_from_sim no)
		(in_bom no)
		(on_board yes)
		(dnp no)
		(fields_autoplaced yes)
		(property "Reference" "MP1"
			(at 335.28 217.17 0)
			(effects
				(font
					(size 1.27 1.27)
					(thickness 0.15)
				)
			)
		)
		(property "Value" "MP_Pad5.4mm_Drill2.7mm"
			(at 335.28 219.71 0)
			(effects
				(font
					(size 1.27 1.27)
					(thickness 0.15)
				)
			)
		)
		(property "Footprint" "antmicro-footprints:MP_Pad5.4mm_Drill2.7mm"
			(at 320.04 217.17 0)
			(effects
				(font
					(size 1.27 1.27)
					(thickness 0.15)
				)
				(justify left bottom)
				(hide yes)
			)
		)
		(property "Datasheet" ""
			(at 323.52 209.22 0)
			(effects
				(font
					(size 1.27 1.27)
					(thickness 0.15)
				)
				(justify left bottom)
				(hide yes)
			)
		)
		(property "Description" "Mechanical part"
			(at 340.36 224.79 0)
			(effects
				(font
					(size 1.27 1.27)
				)
				(hide yes)
			)
		)
		(property "Author" "Antmicro"
			(at 320.04 214.63 0)
			(effects
				(font
					(size 1.27 1.27)
					(thickness 0.15)
				)
				(justify left bottom)
				(hide yes)
			)
		)
		(property "License" "Apache-2.0"
			(at 320.04 212.09 0)
			(effects
				(font
					(size 1.27 1.27)
					(thickness 0.15)
				)
				(justify left bottom)
				(hide yes)
			)
		)
		(pin "1"
		)
		(instances
			(project ""
				(path ""
					(reference "MP1")
					(unit 1)
				)
			)
		)
	)
	(symbol
		(lib_id "antmicropower:PWR_FLAG")
		(at 35.56 120.65 0)
		(unit 1)
		(exclude_from_sim no)
		(in_bom yes)
		(on_board yes)
		(dnp no)
		(property "Reference" "#FLG04"
			(at 35.56 118.745 0)
			(effects
				(font
					(size 1.27 1.27)
				)
				(hide yes)
			)
		)
		(property "Value" "PWR_FLAG"
			(at 35.814 116.84 0)
			(effects
				(font
					(size 1.27 1.27)
				)
			)
		)
		(property "Footprint" ""
			(at 35.56 120.65 0)
			(effects
				(font
					(size 1.27 1.27)
				)
				(hide yes)
			)
		)
		(property "Datasheet" ""
			(at 35.56 120.65 0)
			(effects
				(font
					(size 1.27 1.27)
				)
				(hide yes)
			)
		)
		(property "Description" ""
			(at 35.56 120.65 0)
			(effects
				(font
					(size 1.27 1.27)
				)
				(hide yes)
			)
		)
		(pin "1"
		)
		(instances
			(project "jetson-orin-baseboard-oculink-expansion"
				(path ""
					(reference "#FLG04")
					(unit 1)
				)
			)
		)
	)
	(symbol
		(lib_id "antmicropower:+3V3")
		(at 191.77 236.22 0)
		(mirror y)
		(unit 1)
		(exclude_from_sim no)
		(in_bom yes)
		(on_board yes)
		(dnp no)
		(property "Reference" "#PWR051"
			(at 176.53 236.22 0)
			(effects
				(font
					(size 1.27 1.27)
					(thickness 0.15)
				)
				(justify left bottom)
				(hide yes)
			)
		)
		(property "Value" "+3V3"
			(at 187.96 234.95 0)
			(effects
				(font
					(size 1.27 1.27)
					(thickness 0.15)
				)
			)
		)
		(property "Footprint" ""
			(at 176.53 243.84 0)
			(effects
				(font
					(size 1.27 1.27)
					(thickness 0.15)
				)
				(justify left bottom)
				(hide yes)
			)
		)
		(property "Datasheet" ""
			(at 176.53 246.38 0)
			(effects
				(font
					(size 1.27 1.27)
					(thickness 0.15)
				)
				(justify left bottom)
				(hide yes)
			)
		)
		(property "Description" ""
			(at 191.77 236.22 0)
			(effects
				(font
					(size 1.27 1.27)
				)
				(hide yes)
			)
		)
		(property "Author" "Antmicro"
			(at 176.53 238.76 0)
			(effects
				(font
					(size 1.27 1.27)
					(thickness 0.15)
				)
				(justify left bottom)
				(hide yes)
			)
		)
		(property "License" "Apache-2.0"
			(at 176.53 241.3 0)
			(effects
				(font
					(size 1.27 1.27)
					(thickness 0.15)
				)
				(justify left bottom)
				(hide yes)
			)
		)
		(pin "1"
		)
		(instances
			(project "jetson-orin-baseboard-oculink-expansion"
				(path ""
					(reference "#PWR051")
					(unit 1)
				)
			)
		)
	)
	(symbol
		(lib_id "antmicroResistors0402:R_0R_0402")
		(at 303.53 121.92 0)
		(unit 1)
		(exclude_from_sim no)
		(in_bom yes)
		(on_board yes)
		(dnp no)
		(property "Reference" "R49"
			(at 302.006 120.65 0)
			(effects
				(font
					(size 1.27 1.27)
					(thickness 0.15)
				)
			)
		)
		(property "Value" "R_0R_0402"
			(at 323.85 134.62 0)
			(effects
				(font
					(size 1.27 1.27)
					(thickness 0.15)
				)
				(justify left bottom)
				(hide yes)
			)
		)
		(property "Footprint" "antmicro-footprints:R_0402_1005Metric"
			(at 323.85 137.16 0)
			(effects
				(font
					(size 1.27 1.27)
					(thickness 0.15)
				)
				(justify left bottom)
				(hide yes)
			)
		)
		(property "Datasheet" "https://industrial.panasonic.com/cdbs/www-data/pdf/RDA0000/AOA0000C301.pdf"
			(at 323.85 139.7 0)
			(effects
				(font
					(size 1.27 1.27)
					(thickness 0.15)
				)
				(justify left bottom)
				(hide yes)
			)
		)
		(property "Description" "SMD Chip Resistor, Jumper, 0 ohm, 100 mW, 0402 [1005 Metric], Thick Film, General Purpose"
			(at 303.53 121.92 0)
			(effects
				(font
					(size 1.27 1.27)
				)
				(hide yes)
			)
		)
		(property "MPN" "ERJ2GE0R00X"
			(at 323.85 142.24 0)
			(effects
				(font
					(size 1.27 1.27)
					(thickness 0.15)
				)
				(justify left bottom)
				(hide yes)
			)
		)
		(property "Manufacturer" "Panasonic"
			(at 323.85 144.78 0)
			(effects
				(font
					(size 1.27 1.27)
					(thickness 0.15)
				)
				(justify left bottom)
				(hide yes)
			)
		)
		(property "License" "Apache-2.0"
			(at 323.85 147.32 0)
			(effects
				(font
					(size 1.27 1.27)
					(thickness 0.15)
				)
				(justify left bottom)
				(hide yes)
			)
		)
		(property "Author" "Antmicro"
			(at 323.85 149.86 0)
			(effects
				(font
					(size 1.27 1.27)
					(thickness 0.15)
				)
				(justify left bottom)
				(hide yes)
			)
		)
		(property "Val" "0R"
			(at 309.626 120.65 0)
			(effects
				(font
					(size 1.27 1.27)
					(thickness 0.15)
				)
			)
		)
		(property "Tolerance" "~"
			(at 323.85 132.08 0)
			(effects
				(font
					(size 1.27 1.27)
				)
				(justify left bottom)
				(hide yes)
			)
		)
		(property "Current" "1A"
			(at 323.85 152.4 0)
			(effects
				(font
					(size 1.27 1.27)
					(thickness 0.15)
				)
				(justify left bottom)
				(hide yes)
			)
		)
		(pin "1"
		)
		(pin "2"
		)
		(instances
			(project "jetson-orin-baseboard-oculink-expansion"
				(path ""
					(reference "R49")
					(unit 1)
				)
			)
		)
	)
	(symbol
		(lib_id "antmicropower:GND")
		(at 147.32 34.29 0)
		(unit 1)
		(exclude_from_sim no)
		(in_bom yes)
		(on_board yes)
		(dnp no)
		(property "Reference" "#PWR033"
			(at 156.21 36.83 0)
			(effects
				(font
					(size 1.27 1.27)
					(thickness 0.15)
				)
				(justify left bottom)
				(hide yes)
			)
		)
		(property "Value" "GND"
			(at 147.32 38.1 0)
			(effects
				(font
					(size 1.27 1.27)
					(thickness 0.15)
				)
			)
		)
		(property "Footprint" ""
			(at 156.21 41.91 0)
			(effects
				(font
					(size 1.27 1.27)
					(thickness 0.15)
				)
				(justify left bottom)
				(hide yes)
			)
		)
		(property "Datasheet" ""
			(at 156.21 46.99 0)
			(effects
				(font
					(size 1.27 1.27)
					(thickness 0.15)
				)
				(justify left bottom)
				(hide yes)
			)
		)
		(property "Description" ""
			(at 147.32 34.29 0)
			(effects
				(font
					(size 1.27 1.27)
				)
				(hide yes)
			)
		)
		(property "Author" "Antmicro"
			(at 156.21 41.91 0)
			(effects
				(font
					(size 1.27 1.27)
					(thickness 0.15)
				)
				(justify left bottom)
				(hide yes)
			)
		)
		(property "License" "Apache-2.0"
			(at 156.21 44.45 0)
			(effects
				(font
					(size 1.27 1.27)
					(thickness 0.15)
				)
				(justify left bottom)
				(hide yes)
			)
		)
		(pin "1"
		)
		(instances
			(project "jetson-orin-baseboard-oculink-expansion"
				(path ""
					(reference "#PWR033")
					(unit 1)
				)
			)
		)
	)
	(symbol
		(lib_id "antmicroResistors0402:R_10k_0402")
		(at 242.57 217.17 90)
		(unit 1)
		(exclude_from_sim no)
		(in_bom yes)
		(on_board yes)
		(dnp no)
		(property "Reference" "R16"
			(at 238.252 212.598 0)
			(effects
				(font
					(size 1.27 1.27)
					(thickness 0.15)
				)
				(justify right)
			)
		)
		(property "Value" "R_10k_0402"
			(at 255.27 196.85 0)
			(effects
				(font
					(size 1.27 1.27)
					(thickness 0.15)
				)
				(justify left bottom)
				(hide yes)
			)
		)
		(property "Footprint" "antmicro-footprints:R_0402_1005Metric"
			(at 257.81 196.85 0)
			(effects
				(font
					(size 1.27 1.27)
					(thickness 0.15)
				)
				(justify left bottom)
				(hide yes)
			)
		)
		(property "Datasheet" "https://www.bourns.com/docs/product-datasheets/cr.pdf"
			(at 260.35 196.85 0)
			(effects
				(font
					(size 1.27 1.27)
					(thickness 0.15)
				)
				(justify left bottom)
				(hide yes)
			)
		)
		(property "Description" "SMD Chip Resistor, 10 kohm, ± 1%, 62.5 mW, 0402 [1005 Metric], Thick Film, General Purpose"
			(at 242.57 217.17 0)
			(effects
				(font
					(size 1.27 1.27)
				)
				(hide yes)
			)
		)
		(property "MPN" "CR0402-FX-1002GLF"
			(at 262.89 196.85 0)
			(effects
				(font
					(size 1.27 1.27)
					(thickness 0.15)
				)
				(justify left bottom)
				(hide yes)
			)
		)
		(property "Manufacturer" "Bourns"
			(at 265.43 196.85 0)
			(effects
				(font
					(size 1.27 1.27)
					(thickness 0.15)
				)
				(justify left bottom)
				(hide yes)
			)
		)
		(property "License" "Apache-2.0"
			(at 267.97 196.85 0)
			(effects
				(font
					(size 1.27 1.27)
					(thickness 0.15)
				)
				(justify left bottom)
				(hide yes)
			)
		)
		(property "Author" "Antmicro"
			(at 270.51 196.85 0)
			(effects
				(font
					(size 1.27 1.27)
					(thickness 0.15)
				)
				(justify left bottom)
				(hide yes)
			)
		)
		(property "Val" "10k"
			(at 240.03 212.852 0)
			(effects
				(font
					(size 1.27 1.27)
					(thickness 0.15)
				)
				(justify right)
			)
		)
		(property "Tolerance" "1%"
			(at 252.73 196.85 0)
			(effects
				(font
					(size 1.27 1.27)
				)
				(justify left bottom)
				(hide yes)
			)
		)
		(pin "2"
		)
		(pin "1"
		)
		(instances
			(project "jetson-orin-baseboard-oculink-expansion"
				(path ""
					(reference "R16")
					(unit 1)
				)
			)
		)
	)
	(symbol
		(lib_id "antmicroResistors0402:R_1k_0402")
		(at 267.97 240.03 90)
		(mirror x)
		(unit 1)
		(exclude_from_sim no)
		(in_bom yes)
		(on_board yes)
		(dnp no)
		(property "Reference" "R6"
			(at 267.97 236.22 0)
			(effects
				(font
					(size 1.27 1.27)
					(thickness 0.15)
				)
				(justify right)
			)
		)
		(property "Value" "R_1k_0402"
			(at 280.67 260.35 0)
			(effects
				(font
					(size 1.27 1.27)
					(thickness 0.15)
				)
				(justify left bottom)
				(hide yes)
			)
		)
		(property "Footprint" "antmicro-footprints:R_0402_1005Metric"
			(at 283.21 260.35 0)
			(effects
				(font
					(size 1.27 1.27)
					(thickness 0.15)
				)
				(justify left bottom)
				(hide yes)
			)
		)
		(property "Datasheet" "https://www.bourns.com/docs/product-datasheets/cr.pdf"
			(at 285.75 260.35 0)
			(effects
				(font
					(size 1.27 1.27)
					(thickness 0.15)
				)
				(justify left bottom)
				(hide yes)
			)
		)
		(property "Description" "SMD Chip Resistor, 1 kohm, ± 1%, 63 mW, 0402 [1005 Metric], Thick Film, General Purpose"
			(at 267.97 240.03 0)
			(effects
				(font
					(size 1.27 1.27)
				)
				(hide yes)
			)
		)
		(property "MPN" "CR0402-FX-1001GLF"
			(at 288.29 260.35 0)
			(effects
				(font
					(size 1.27 1.27)
					(thickness 0.15)
				)
				(justify left bottom)
				(hide yes)
			)
		)
		(property "Manufacturer" "Bourns"
			(at 290.83 260.35 0)
			(effects
				(font
					(size 1.27 1.27)
					(thickness 0.15)
				)
				(justify left bottom)
				(hide yes)
			)
		)
		(property "License" "Apache-2.0"
			(at 293.37 260.35 0)
			(effects
				(font
					(size 1.27 1.27)
					(thickness 0.15)
				)
				(justify left bottom)
				(hide yes)
			)
		)
		(property "Author" "Antmicro"
			(at 295.91 260.35 0)
			(effects
				(font
					(size 1.27 1.27)
					(thickness 0.15)
				)
				(justify left bottom)
				(hide yes)
			)
		)
		(property "Val" "1k"
			(at 266.7 240.03 0)
			(effects
				(font
					(size 1.27 1.27)
					(thickness 0.15)
				)
				(justify right)
			)
		)
		(property "Tolerance" "1%"
			(at 278.13 260.35 0)
			(effects
				(font
					(size 1.27 1.27)
				)
				(justify left bottom)
				(hide yes)
			)
		)
		(property "Public" "False"
			(at 298.45 260.35 0)
			(effects
				(font
					(size 1.27 1.27)
				)
				(justify left bottom)
				(hide yes)
			)
		)
		(pin "1"
		)
		(pin "2"
		)
		(instances
			(project "jetson-orin-baseboard-oculink-expansion"
				(path ""
					(reference "R6")
					(unit 1)
				)
			)
		)
	)
	(symbol
		(lib_id "antmicroResistors0402:R_0R_0402")
		(at 256.54 218.44 0)
		(mirror y)
		(unit 1)
		(exclude_from_sim no)
		(in_bom yes)
		(on_board yes)
		(dnp yes)
		(property "Reference" "R36"
			(at 251.968 215.9 0)
			(effects
				(font
					(size 1.27 1.27)
					(thickness 0.15)
				)
				(justify right)
			)
		)
		(property "Value" "R_0R_0402"
			(at 236.22 231.14 0)
			(effects
				(font
					(size 1.27 1.27)
					(thickness 0.15)
				)
				(justify left bottom)
				(hide yes)
			)
		)
		(property "Footprint" "antmicro-footprints:R_0402_1005Metric"
			(at 236.22 233.68 0)
			(effects
				(font
					(size 1.27 1.27)
					(thickness 0.15)
				)
				(justify left bottom)
				(hide yes)
			)
		)
		(property "Datasheet" "https://industrial.panasonic.com/cdbs/www-data/pdf/RDA0000/AOA0000C301.pdf"
			(at 236.22 236.22 0)
			(effects
				(font
					(size 1.27 1.27)
					(thickness 0.15)
				)
				(justify left bottom)
				(hide yes)
			)
		)
		(property "Description" "SMD Chip Resistor, Jumper, 0 ohm, 100 mW, 0402 [1005 Metric], Thick Film, General Purpose"
			(at 256.54 218.44 0)
			(effects
				(font
					(size 1.27 1.27)
				)
				(hide yes)
			)
		)
		(property "MPN" "ERJ2GE0R00X"
			(at 236.22 238.76 0)
			(effects
				(font
					(size 1.27 1.27)
					(thickness 0.15)
				)
				(justify left bottom)
				(hide yes)
			)
		)
		(property "Manufacturer" "Panasonic"
			(at 236.22 241.3 0)
			(effects
				(font
					(size 1.27 1.27)
					(thickness 0.15)
				)
				(justify left bottom)
				(hide yes)
			)
		)
		(property "License" "Apache-2.0"
			(at 236.22 243.84 0)
			(effects
				(font
					(size 1.27 1.27)
					(thickness 0.15)
				)
				(justify left bottom)
				(hide yes)
			)
		)
		(property "Author" "Antmicro"
			(at 236.22 246.38 0)
			(effects
				(font
					(size 1.27 1.27)
					(thickness 0.15)
				)
				(justify left bottom)
				(hide yes)
			)
		)
		(property "Val" "0R"
			(at 253.238 214.122 0)
			(effects
				(font
					(size 1.27 1.27)
					(thickness 0.15)
				)
				(justify right)
			)
		)
		(property "Tolerance" "~"
			(at 236.22 228.6 0)
			(effects
				(font
					(size 1.27 1.27)
				)
				(justify left bottom)
				(hide yes)
			)
		)
		(property "Current" "1A"
			(at 236.22 248.92 0)
			(effects
				(font
					(size 1.27 1.27)
					(thickness 0.15)
				)
				(justify left bottom)
				(hide yes)
			)
		)
		(property "Public" "False"
			(at 236.22 248.92 0)
			(effects
				(font
					(size 1.27 1.27)
				)
				(justify left bottom)
				(hide yes)
			)
		)
		(pin "1"
		)
		(pin "2"
		)
		(instances
			(project "jetson-orin-baseboard-oculink-expansion"
				(path ""
					(reference "R36")
					(unit 1)
				)
			)
		)
	)
	(symbol
		(lib_id "antmicropower:GND")
		(at 224.79 127 0)
		(unit 1)
		(exclude_from_sim no)
		(in_bom yes)
		(on_board yes)
		(dnp no)
		(property "Reference" "#PWR054"
			(at 233.68 129.54 0)
			(effects
				(font
					(size 1.27 1.27)
					(thickness 0.15)
				)
				(justify left bottom)
				(hide yes)
			)
		)
		(property "Value" "GND"
			(at 224.79 130.81 0)
			(effects
				(font
					(size 1.27 1.27)
					(thickness 0.15)
				)
			)
		)
		(property "Footprint" ""
			(at 233.68 134.62 0)
			(effects
				(font
					(size 1.27 1.27)
					(thickness 0.15)
				)
				(justify left bottom)
				(hide yes)
			)
		)
		(property "Datasheet" ""
			(at 233.68 139.7 0)
			(effects
				(font
					(size 1.27 1.27)
					(thickness 0.15)
				)
				(justify left bottom)
				(hide yes)
			)
		)
		(property "Description" ""
			(at 224.79 127 0)
			(effects
				(font
					(size 1.27 1.27)
				)
				(hide yes)
			)
		)
		(property "Author" "Antmicro"
			(at 233.68 134.62 0)
			(effects
				(font
					(size 1.27 1.27)
					(thickness 0.15)
				)
				(justify left bottom)
				(hide yes)
			)
		)
		(property "License" "Apache-2.0"
			(at 233.68 137.16 0)
			(effects
				(font
					(size 1.27 1.27)
					(thickness 0.15)
				)
				(justify left bottom)
				(hide yes)
			)
		)
		(pin "1"
		)
		(instances
			(project "jetson-orin-baseboard-oculink-expansion"
				(path ""
					(reference "#PWR054")
					(unit 1)
				)
			)
		)
	)
	(symbol
		(lib_id "antmicropower:PWR_FLAG")
		(at 35.56 128.27 0)
		(unit 1)
		(exclude_from_sim no)
		(in_bom yes)
		(on_board yes)
		(dnp no)
		(property "Reference" "#FLG01"
			(at 35.56 126.365 0)
			(effects
				(font
					(size 1.27 1.27)
				)
				(hide yes)
			)
		)
		(property "Value" "PWR_FLAG"
			(at 35.814 124.46 0)
			(effects
				(font
					(size 1.27 1.27)
				)
			)
		)
		(property "Footprint" ""
			(at 35.56 128.27 0)
			(effects
				(font
					(size 1.27 1.27)
				)
				(hide yes)
			)
		)
		(property "Datasheet" ""
			(at 35.56 128.27 0)
			(effects
				(font
					(size 1.27 1.27)
				)
				(hide yes)
			)
		)
		(property "Description" ""
			(at 35.56 128.27 0)
			(effects
				(font
					(size 1.27 1.27)
				)
				(hide yes)
			)
		)
		(pin "1"
		)
		(instances
			(project ""
				(path ""
					(reference "#FLG01")
					(unit 1)
				)
			)
		)
	)
	(symbol
		(lib_id "antmicropower:GND")
		(at 181.61 187.96 0)
		(mirror y)
		(unit 1)
		(exclude_from_sim no)
		(in_bom yes)
		(on_board yes)
		(dnp no)
		(property "Reference" "#PWR025"
			(at 172.72 190.5 0)
			(effects
				(font
					(size 1.27 1.27)
					(thickness 0.15)
				)
				(justify left bottom)
				(hide yes)
			)
		)
		(property "Value" "GND"
			(at 181.61 191.77 0)
			(effects
				(font
					(size 1.27 1.27)
					(thickness 0.15)
				)
			)
		)
		(property "Footprint" ""
			(at 172.72 195.58 0)
			(effects
				(font
					(size 1.27 1.27)
					(thickness 0.15)
				)
				(justify left bottom)
				(hide yes)
			)
		)
		(property "Datasheet" ""
			(at 172.72 200.66 0)
			(effects
				(font
					(size 1.27 1.27)
					(thickness 0.15)
				)
				(justify left bottom)
				(hide yes)
			)
		)
		(property "Description" ""
			(at 181.61 187.96 0)
			(effects
				(font
					(size 1.27 1.27)
				)
				(hide yes)
			)
		)
		(property "Author" "Antmicro"
			(at 172.72 195.58 0)
			(effects
				(font
					(size 1.27 1.27)
					(thickness 0.15)
				)
				(justify left bottom)
				(hide yes)
			)
		)
		(property "License" "Apache-2.0"
			(at 172.72 198.12 0)
			(effects
				(font
					(size 1.27 1.27)
					(thickness 0.15)
				)
				(justify left bottom)
				(hide yes)
			)
		)
		(pin "1"
		)
		(instances
			(project "jetson-orin-baseboard-oculink-expansion"
				(path ""
					(reference "#PWR025")
					(unit 1)
				)
			)
		)
	)
	(symbol
		(lib_id "antmicroResistors0402:R_1k_0402")
		(at 270.51 269.24 270)
		(mirror x)
		(unit 1)
		(exclude_from_sim no)
		(in_bom yes)
		(on_board yes)
		(dnp no)
		(property "Reference" "R5"
			(at 270.51 273.05 0)
			(effects
				(font
					(size 1.27 1.27)
					(thickness 0.15)
				)
				(justify right)
			)
		)
		(property "Value" "R_1k_0402"
			(at 257.81 248.92 0)
			(effects
				(font
					(size 1.27 1.27)
					(thickness 0.15)
				)
				(justify left bottom)
				(hide yes)
			)
		)
		(property "Footprint" "antmicro-footprints:R_0402_1005Metric"
			(at 255.27 248.92 0)
			(effects
				(font
					(size 1.27 1.27)
					(thickness 0.15)
				)
				(justify left bottom)
				(hide yes)
			)
		)
		(property "Datasheet" "https://www.bourns.com/docs/product-datasheets/cr.pdf"
			(at 252.73 248.92 0)
			(effects
				(font
					(size 1.27 1.27)
					(thickness 0.15)
				)
				(justify left bottom)
				(hide yes)
			)
		)
		(property "Description" "SMD Chip Resistor, 1 kohm, ± 1%, 63 mW, 0402 [1005 Metric], Thick Film, General Purpose"
			(at 270.51 269.24 0)
			(effects
				(font
					(size 1.27 1.27)
				)
				(hide yes)
			)
		)
		(property "MPN" "CR0402-FX-1001GLF"
			(at 250.19 248.92 0)
			(effects
				(font
					(size 1.27 1.27)
					(thickness 0.15)
				)
				(justify left bottom)
				(hide yes)
			)
		)
		(property "Manufacturer" "Bourns"
			(at 247.65 248.92 0)
			(effects
				(font
					(size 1.27 1.27)
					(thickness 0.15)
				)
				(justify left bottom)
				(hide yes)
			)
		)
		(property "License" "Apache-2.0"
			(at 245.11 248.92 0)
			(effects
				(font
					(size 1.27 1.27)
					(thickness 0.15)
				)
				(justify left bottom)
				(hide yes)
			)
		)
		(property "Author" "Antmicro"
			(at 242.57 248.92 0)
			(effects
				(font
					(size 1.27 1.27)
					(thickness 0.15)
				)
				(justify left bottom)
				(hide yes)
			)
		)
		(property "Val" "1k"
			(at 271.78 269.24 0)
			(effects
				(font
					(size 1.27 1.27)
					(thickness 0.15)
				)
				(justify right)
			)
		)
		(property "Tolerance" "1%"
			(at 260.35 248.92 0)
			(effects
				(font
					(size 1.27 1.27)
				)
				(justify left bottom)
				(hide yes)
			)
		)
		(property "Public" "False"
			(at 240.03 248.92 0)
			(effects
				(font
					(size 1.27 1.27)
				)
				(justify left bottom)
				(hide yes)
			)
		)
		(pin "1"
		)
		(pin "2"
		)
		(instances
			(project "jetson-orin-baseboard-oculink-expansion"
				(path ""
					(reference "R5")
					(unit 1)
				)
			)
		)
	)
	(symbol
		(lib_id "antmicroResistors0402:R_0R_0402")
		(at 193.04 237.49 0)
		(mirror x)
		(unit 1)
		(exclude_from_sim no)
		(in_bom yes)
		(on_board yes)
		(dnp no)
		(property "Reference" "R18"
			(at 195.58 240.03 0)
			(effects
				(font
					(size 1.27 1.27)
					(thickness 0.15)
				)
			)
		)
		(property "Value" "R_0R_0402"
			(at 213.36 224.79 0)
			(effects
				(font
					(size 1.27 1.27)
					(thickness 0.15)
				)
				(justify left bottom)
				(hide yes)
			)
		)
		(property "Footprint" "antmicro-footprints:R_0402_1005Metric"
			(at 213.36 222.25 0)
			(effects
				(font
					(size 1.27 1.27)
					(thickness 0.15)
				)
				(justify left bottom)
				(hide yes)
			)
		)
		(property "Datasheet" "https://industrial.panasonic.com/cdbs/www-data/pdf/RDA0000/AOA0000C301.pdf"
			(at 213.36 219.71 0)
			(effects
				(font
					(size 1.27 1.27)
					(thickness 0.15)
				)
				(justify left bottom)
				(hide yes)
			)
		)
		(property "Description" "SMD Chip Resistor, Jumper, 0 ohm, 100 mW, 0402 [1005 Metric], Thick Film, General Purpose"
			(at 193.04 237.49 0)
			(effects
				(font
					(size 1.27 1.27)
				)
				(hide yes)
			)
		)
		(property "MPN" "ERJ2GE0R00X"
			(at 213.36 217.17 0)
			(effects
				(font
					(size 1.27 1.27)
					(thickness 0.15)
				)
				(justify left bottom)
				(hide yes)
			)
		)
		(property "Manufacturer" "Panasonic"
			(at 213.36 214.63 0)
			(effects
				(font
					(size 1.27 1.27)
					(thickness 0.15)
				)
				(justify left bottom)
				(hide yes)
			)
		)
		(property "License" "Apache-2.0"
			(at 213.36 212.09 0)
			(effects
				(font
					(size 1.27 1.27)
					(thickness 0.15)
				)
				(justify left bottom)
				(hide yes)
			)
		)
		(property "Author" "Antmicro"
			(at 213.36 209.55 0)
			(effects
				(font
					(size 1.27 1.27)
					(thickness 0.15)
				)
				(justify left bottom)
				(hide yes)
			)
		)
		(property "Val" "0R"
			(at 195.58 242.57 0)
			(effects
				(font
					(size 1.27 1.27)
					(thickness 0.15)
				)
			)
		)
		(property "Tolerance" "~"
			(at 213.36 227.33 0)
			(effects
				(font
					(size 1.27 1.27)
				)
				(justify left bottom)
				(hide yes)
			)
		)
		(property "Current" "1A"
			(at 213.36 207.01 0)
			(effects
				(font
					(size 1.27 1.27)
					(thickness 0.15)
				)
				(justify left bottom)
				(hide yes)
			)
		)
		(property "Public" "False"
			(at 213.36 207.01 0)
			(effects
				(font
					(size 1.27 1.27)
				)
				(justify left bottom)
				(hide yes)
			)
		)
		(pin "1"
		)
		(pin "2"
		)
		(instances
			(project "jetson-orin-baseboard-oculink-expansion"
				(path ""
					(reference "R18")
					(unit 1)
				)
			)
		)
	)
	(symbol
		(lib_id "antmicroResistors0402:R_1k_0402")
		(at 262.89 269.24 270)
		(mirror x)
		(unit 1)
		(exclude_from_sim no)
		(in_bom yes)
		(on_board yes)
		(dnp no)
		(property "Reference" "R11"
			(at 262.89 273.05 0)
			(effects
				(font
					(size 1.27 1.27)
					(thickness 0.15)
				)
				(justify right)
			)
		)
		(property "Value" "R_1k_0402"
			(at 250.19 248.92 0)
			(effects
				(font
					(size 1.27 1.27)
					(thickness 0.15)
				)
				(justify left bottom)
				(hide yes)
			)
		)
		(property "Footprint" "antmicro-footprints:R_0402_1005Metric"
			(at 247.65 248.92 0)
			(effects
				(font
					(size 1.27 1.27)
					(thickness 0.15)
				)
				(justify left bottom)
				(hide yes)
			)
		)
		(property "Datasheet" "https://www.bourns.com/docs/product-datasheets/cr.pdf"
			(at 245.11 248.92 0)
			(effects
				(font
					(size 1.27 1.27)
					(thickness 0.15)
				)
				(justify left bottom)
				(hide yes)
			)
		)
		(property "Description" "SMD Chip Resistor, 1 kohm, ± 1%, 63 mW, 0402 [1005 Metric], Thick Film, General Purpose"
			(at 262.89 269.24 0)
			(effects
				(font
					(size 1.27 1.27)
				)
				(hide yes)
			)
		)
		(property "MPN" "CR0402-FX-1001GLF"
			(at 242.57 248.92 0)
			(effects
				(font
					(size 1.27 1.27)
					(thickness 0.15)
				)
				(justify left bottom)
				(hide yes)
			)
		)
		(property "Manufacturer" "Bourns"
			(at 240.03 248.92 0)
			(effects
				(font
					(size 1.27 1.27)
					(thickness 0.15)
				)
				(justify left bottom)
				(hide yes)
			)
		)
		(property "License" "Apache-2.0"
			(at 237.49 248.92 0)
			(effects
				(font
					(size 1.27 1.27)
					(thickness 0.15)
				)
				(justify left bottom)
				(hide yes)
			)
		)
		(property "Author" "Antmicro"
			(at 234.95 248.92 0)
			(effects
				(font
					(size 1.27 1.27)
					(thickness 0.15)
				)
				(justify left bottom)
				(hide yes)
			)
		)
		(property "Val" "1k"
			(at 264.16 269.24 0)
			(effects
				(font
					(size 1.27 1.27)
					(thickness 0.15)
				)
				(justify right)
			)
		)
		(property "Tolerance" "1%"
			(at 252.73 248.92 0)
			(effects
				(font
					(size 1.27 1.27)
				)
				(justify left bottom)
				(hide yes)
			)
		)
		(property "Public" "False"
			(at 232.41 248.92 0)
			(effects
				(font
					(size 1.27 1.27)
				)
				(justify left bottom)
				(hide yes)
			)
		)
		(pin "1"
		)
		(pin "2"
		)
		(instances
			(project "jetson-orin-baseboard-oculink-expansion"
				(path ""
					(reference "R11")
					(unit 1)
				)
			)
		)
	)
	(symbol
		(lib_id "antmicropower:+3V3")
		(at 246.38 228.6 0)
		(mirror y)
		(unit 1)
		(exclude_from_sim no)
		(in_bom yes)
		(on_board yes)
		(dnp no)
		(property "Reference" "#PWR058"
			(at 231.14 228.6 0)
			(effects
				(font
					(size 1.27 1.27)
					(thickness 0.15)
				)
				(justify left bottom)
				(hide yes)
			)
		)
		(property "Value" "+3V3"
			(at 250.19 227.33 0)
			(effects
				(font
					(size 1.27 1.27)
					(thickness 0.15)
				)
			)
		)
		(property "Footprint" ""
			(at 231.14 236.22 0)
			(effects
				(font
					(size 1.27 1.27)
					(thickness 0.15)
				)
				(justify left bottom)
				(hide yes)
			)
		)
		(property "Datasheet" ""
			(at 231.14 238.76 0)
			(effects
				(font
					(size 1.27 1.27)
					(thickness 0.15)
				)
				(justify left bottom)
				(hide yes)
			)
		)
		(property "Description" ""
			(at 246.38 228.6 0)
			(effects
				(font
					(size 1.27 1.27)
				)
				(hide yes)
			)
		)
		(property "Author" "Antmicro"
			(at 231.14 231.14 0)
			(effects
				(font
					(size 1.27 1.27)
					(thickness 0.15)
				)
				(justify left bottom)
				(hide yes)
			)
		)
		(property "License" "Apache-2.0"
			(at 231.14 233.68 0)
			(effects
				(font
					(size 1.27 1.27)
					(thickness 0.15)
				)
				(justify left bottom)
				(hide yes)
			)
		)
		(pin "1"
		)
		(instances
			(project "jetson-orin-baseboard-oculink-expansion"
				(path ""
					(reference "#PWR058")
					(unit 1)
				)
			)
		)
	)
	(symbol
		(lib_id "antmicropower:GND")
		(at 146.05 172.72 0)
		(mirror y)
		(unit 1)
		(exclude_from_sim no)
		(in_bom yes)
		(on_board yes)
		(dnp no)
		(property "Reference" "#PWR040"
			(at 137.16 175.26 0)
			(effects
				(font
					(size 1.27 1.27)
					(thickness 0.15)
				)
				(justify left bottom)
				(hide yes)
			)
		)
		(property "Value" "GND"
			(at 146.05 176.53 0)
			(effects
				(font
					(size 1.27 1.27)
					(thickness 0.15)
				)
			)
		)
		(property "Footprint" ""
			(at 137.16 180.34 0)
			(effects
				(font
					(size 1.27 1.27)
					(thickness 0.15)
				)
				(justify left bottom)
				(hide yes)
			)
		)
		(property "Datasheet" ""
			(at 137.16 185.42 0)
			(effects
				(font
					(size 1.27 1.27)
					(thickness 0.15)
				)
				(justify left bottom)
				(hide yes)
			)
		)
		(property "Description" ""
			(at 146.05 172.72 0)
			(effects
				(font
					(size 1.27 1.27)
				)
				(hide yes)
			)
		)
		(property "Author" "Antmicro"
			(at 137.16 180.34 0)
			(effects
				(font
					(size 1.27 1.27)
					(thickness 0.15)
				)
				(justify left bottom)
				(hide yes)
			)
		)
		(property "License" "Apache-2.0"
			(at 137.16 182.88 0)
			(effects
				(font
					(size 1.27 1.27)
					(thickness 0.15)
				)
				(justify left bottom)
				(hide yes)
			)
		)
		(pin "1"
		)
		(instances
			(project "jetson-orin-baseboard-oculink-expansion"
				(path ""
					(reference "#PWR040")
					(unit 1)
				)
			)
		)
	)
	(symbol
		(lib_id "antmicropower:GND")
		(at 345.44 168.91 0)
		(unit 1)
		(exclude_from_sim no)
		(in_bom yes)
		(on_board yes)
		(dnp no)
		(fields_autoplaced yes)
		(property "Reference" "#PWR021"
			(at 345.44 175.26 0)
			(effects
				(font
					(size 1.27 1.27)
				)
				(justify left bottom)
				(hide yes)
			)
		)
		(property "Value" "GND"
			(at 345.44 172.72 0)
			(effects
				(font
					(size 1.27 1.27)
					(thickness 0.15)
				)
			)
		)
		(property "Footprint" ""
			(at 354.33 176.53 0)
			(effects
				(font
					(size 1.27 1.27)
					(thickness 0.15)
				)
				(justify left bottom)
				(hide yes)
			)
		)
		(property "Datasheet" ""
			(at 354.33 181.61 0)
			(effects
				(font
					(size 1.27 1.27)
					(thickness 0.15)
				)
				(justify left bottom)
				(hide yes)
			)
		)
		(property "Description" ""
			(at 345.44 168.91 0)
			(effects
				(font
					(size 1.27 1.27)
				)
				(hide yes)
			)
		)
		(property "Author" "Antmicro"
			(at 354.33 176.53 0)
			(effects
				(font
					(size 1.27 1.27)
					(thickness 0.15)
				)
				(justify left bottom)
				(hide yes)
			)
		)
		(property "License" "Apache-2.0"
			(at 354.33 179.07 0)
			(effects
				(font
					(size 1.27 1.27)
					(thickness 0.15)
				)
				(justify left bottom)
				(hide yes)
			)
		)
		(pin "1"
		)
		(instances
			(project "jetson-orin-baseboard-oculink-expansion"
				(path ""
					(reference "#PWR021")
					(unit 1)
				)
			)
		)
	)
	(symbol
		(lib_id "antmicroTestPoints:TP_1.5mm_SMD")
		(at 33.02 121.92 180)
		(unit 1)
		(exclude_from_sim no)
		(in_bom no)
		(on_board yes)
		(dnp no)
		(property "Reference" "TP10"
			(at 26.67 121.92 0)
			(effects
				(font
					(size 1.27 1.27)
					(thickness 0.15)
				)
			)
		)
		(property "Value" "TP_1.5mm_SMD"
			(at 17.78 114.3 0)
			(effects
				(font
					(size 1.27 1.27)
					(thickness 0.15)
				)
				(justify left bottom)
				(hide yes)
			)
		)
		(property "Footprint" "antmicro-footprints:TP_SMD_1.5mm"
			(at 17.78 111.76 0)
			(effects
				(font
					(size 1.27 1.27)
					(thickness 0.15)
				)
				(justify left bottom)
				(hide yes)
			)
		)
		(property "Datasheet" ""
			(at 15.24 109.22 0)
			(effects
				(font
					(size 1.27 1.27)
					(thickness 0.15)
				)
				(justify left bottom)
				(hide yes)
			)
		)
		(property "Description" "test point, SMT"
			(at 33.02 121.92 0)
			(effects
				(font
					(size 1.27 1.27)
				)
				(hide yes)
			)
		)
		(property "MPN" ""
			(at 33.02 121.92 0)
			(effects
				(font
					(size 1.27 1.27)
				)
				(hide yes)
			)
		)
		(property "Manufacturer" ""
			(at 33.02 121.92 0)
			(effects
				(font
					(size 1.27 1.27)
				)
				(hide yes)
			)
		)
		(property "Author" "Antmicro"
			(at 17.78 106.68 0)
			(effects
				(font
					(size 1.27 1.27)
					(thickness 0.15)
				)
				(justify left bottom)
				(hide yes)
			)
		)
		(property "License" "Apache-2.0"
			(at 17.78 104.14 0)
			(effects
				(font
					(size 1.27 1.27)
					(thickness 0.15)
				)
				(justify left bottom)
				(hide yes)
			)
		)
		(pin "1"
		)
		(instances
			(project "jetson-orin-baseboard-oculink-expansion"
				(path ""
					(reference "TP10")
					(unit 1)
				)
			)
		)
	)
	(symbol
		(lib_id "antmicroCapacitors0402:C_100n_0402")
		(at 146.05 172.72 270)
		(mirror x)
		(unit 1)
		(exclude_from_sim no)
		(in_bom yes)
		(on_board yes)
		(dnp no)
		(fields_autoplaced yes)
		(property "Reference" "C27"
			(at 143.51 168.9036 90)
			(effects
				(font
					(size 1.27 1.27)
					(thickness 0.15)
				)
				(justify right)
			)
		)
		(property "Value" "C_100n_0402"
			(at 135.89 152.4 0)
			(effects
				(font
					(size 1.27 1.27)
					(thickness 0.15)
				)
				(justify left bottom)
				(hide yes)
			)
		)
		(property "Footprint" "antmicro-footprints:C_0402_1005Metric"
			(at 133.35 152.4 0)
			(effects
				(font
					(size 1.27 1.27)
					(thickness 0.15)
				)
				(justify left bottom)
				(hide yes)
			)
		)
		(property "Datasheet" "https://www.murata.com/products/productdetail?partno=GRM155R61H104KE14%23"
			(at 130.81 152.4 0)
			(effects
				(font
					(size 1.27 1.27)
					(thickness 0.15)
				)
				(justify left bottom)
				(hide yes)
			)
		)
		(property "Description" "SMD Multilayer Ceramic Capacitor, 0.1 µF, 50 V, 0402 [1005 Metric], ± 10%, X5R, GRM Series"
			(at 146.05 172.72 0)
			(effects
				(font
					(size 1.27 1.27)
				)
				(hide yes)
			)
		)
		(property "MPN" "GRM155R61H104KE14D"
			(at 128.27 152.4 0)
			(effects
				(font
					(size 1.27 1.27)
					(thickness 0.15)
				)
				(justify left bottom)
				(hide yes)
			)
		)
		(property "Manufacturer" "Murata"
			(at 125.73 152.4 0)
			(effects
				(font
					(size 1.27 1.27)
					(thickness 0.15)
				)
				(justify left bottom)
				(hide yes)
			)
		)
		(property "License" "Apache-2.0"
			(at 123.19 152.4 0)
			(effects
				(font
					(size 1.27 1.27)
					(thickness 0.15)
				)
				(justify left bottom)
				(hide yes)
			)
		)
		(property "Author" "Antmicro"
			(at 120.65 152.4 0)
			(effects
				(font
					(size 1.27 1.27)
					(thickness 0.15)
				)
				(justify left bottom)
				(hide yes)
			)
		)
		(property "Val" "100n"
			(at 143.51 171.4436 90)
			(effects
				(font
					(size 1.27 1.27)
					(thickness 0.15)
				)
				(justify right)
			)
		)
		(property "Voltage" "50V"
			(at 118.11 152.4 0)
			(effects
				(font
					(size 1.27 1.27)
				)
				(justify left bottom)
				(hide yes)
			)
		)
		(property "Dielectric" "X5R"
			(at 115.57 152.4 0)
			(effects
				(font
					(size 1.27 1.27)
				)
				(justify left bottom)
				(hide yes)
			)
		)
		(property "Public" "False"
			(at 113.03 152.4 0)
			(effects
				(font
					(size 1.27 1.27)
				)
				(justify left bottom)
				(hide yes)
			)
		)
		(pin "1"
		)
		(pin "2"
		)
		(instances
			(project "jetson-orin-baseboard-oculink-expansion"
				(path ""
					(reference "C27")
					(unit 1)
				)
			)
		)
	)
	(symbol
		(lib_id "antmicroInterfaceDriversReceiversTransceivers:PI3EQX16904GL")
		(at 200.66 58.42 0)
		(unit 1)
		(exclude_from_sim no)
		(in_bom yes)
		(on_board yes)
		(dnp no)
		(property "Reference" "U3"
			(at 212.09 50.8 0)
			(effects
				(font
					(size 1.27 1.27)
					(thickness 0.15)
				)
			)
		)
		(property "Value" "PI3EQX16904GL"
			(at 236.22 68.58 0)
			(effects
				(font
					(size 1.27 1.27)
					(thickness 0.15)
				)
				(justify left bottom)
				(hide yes)
			)
		)
		(property "Footprint" "antmicro-footprints:WQFN-42-1EP_3.5x9mm_P0.5mm"
			(at 236.22 71.12 0)
			(effects
				(font
					(size 1.27 1.27)
					(thickness 0.15)
				)
				(justify left bottom)
				(hide yes)
			)
		)
		(property "Datasheet" "https://www.diodes.com/part/view/PI3EQX16904GL"
			(at 236.22 73.66 0)
			(effects
				(font
					(size 1.27 1.27)
					(thickness 0.15)
				)
				(justify left bottom)
				(hide yes)
			)
		)
		(property "Description" "16Gbps 4-Channel ReDriver with Linear Equalization"
			(at 200.66 58.42 0)
			(effects
				(font
					(size 1.27 1.27)
				)
				(hide yes)
			)
		)
		(property "MPN" "PI3EQX16904GLZHEX"
			(at 212.09 53.34 0)
			(effects
				(font
					(size 1.27 1.27)
					(thickness 0.15)
				)
			)
		)
		(property "Manufacturer" "Diodes Incorporated"
			(at 236.22 66.04 0)
			(effects
				(font
					(size 1.27 1.27)
					(thickness 0.15)
				)
				(justify left bottom)
				(hide yes)
			)
		)
		(property "Author" "Antmicro"
			(at 236.22 76.2 0)
			(effects
				(font
					(size 1.27 1.27)
					(thickness 0.15)
				)
				(justify left bottom)
				(hide yes)
			)
		)
		(property "License" "Apache-2.0"
			(at 236.22 78.74 0)
			(effects
				(font
					(size 1.27 1.27)
					(thickness 0.15)
				)
				(justify left bottom)
				(hide yes)
			)
		)
		(pin "9"
		)
		(pin "29"
		)
		(pin "30"
		)
		(pin "4"
		)
		(pin "20"
		)
		(pin "33"
		)
		(pin "3"
		)
		(pin "19"
		)
		(pin "25"
		)
		(pin "34"
		)
		(pin "31"
		)
		(pin "23"
		)
		(pin "26"
		)
		(pin "27"
		)
		(pin "42"
		)
		(pin "41"
		)
		(pin "24"
		)
		(pin "2"
		)
		(pin "39"
		)
		(pin "28"
		)
		(pin "7"
		)
		(pin "36"
		)
		(pin "43"
		)
		(pin "38"
		)
		(pin "8"
		)
		(pin "5"
		)
		(pin "6"
		)
		(pin "37"
		)
		(pin "40"
		)
		(pin "35"
		)
		(pin "18"
		)
		(pin "21"
		)
		(pin "17"
		)
		(pin "10"
		)
		(pin "1"
		)
		(pin "16"
		)
		(pin "15"
		)
		(pin "14"
		)
		(pin "13"
		)
		(pin "12"
		)
		(pin "11"
		)
		(pin "32"
		)
		(pin "22"
		)
		(instances
			(project "jetson-orin-baseboard-oculink-expansion"
				(path ""
					(reference "U3")
					(unit 1)
				)
			)
		)
	)
	(symbol
		(lib_id "antmicroTestPoints:TP_1.5mm_SMD")
		(at 33.02 114.3 180)
		(unit 1)
		(exclude_from_sim no)
		(in_bom no)
		(on_board yes)
		(dnp no)
		(property "Reference" "TP8"
			(at 26.035 114.3 0)
			(effects
				(font
					(size 1.27 1.27)
					(thickness 0.15)
				)
			)
		)
		(property "Value" "TP_1.5mm_SMD"
			(at 17.78 106.68 0)
			(effects
				(font
					(size 1.27 1.27)
					(thickness 0.15)
				)
				(justify left bottom)
				(hide yes)
			)
		)
		(property "Footprint" "antmicro-footprints:TP_SMD_1.5mm"
			(at 17.78 104.14 0)
			(effects
				(font
					(size 1.27 1.27)
					(thickness 0.15)
				)
				(justify left bottom)
				(hide yes)
			)
		)
		(property "Datasheet" ""
			(at 15.24 101.6 0)
			(effects
				(font
					(size 1.27 1.27)
					(thickness 0.15)
				)
				(justify left bottom)
				(hide yes)
			)
		)
		(property "Description" "test point, SMT"
			(at 33.02 114.3 0)
			(effects
				(font
					(size 1.27 1.27)
				)
				(hide yes)
			)
		)
		(property "MPN" ""
			(at 33.02 114.3 0)
			(effects
				(font
					(size 1.27 1.27)
				)
				(hide yes)
			)
		)
		(property "Manufacturer" ""
			(at 33.02 114.3 0)
			(effects
				(font
					(size 1.27 1.27)
				)
				(hide yes)
			)
		)
		(property "Author" "Antmicro"
			(at 17.78 99.06 0)
			(effects
				(font
					(size 1.27 1.27)
					(thickness 0.15)
				)
				(justify left bottom)
				(hide yes)
			)
		)
		(property "License" "Apache-2.0"
			(at 17.78 96.52 0)
			(effects
				(font
					(size 1.27 1.27)
					(thickness 0.15)
				)
				(justify left bottom)
				(hide yes)
			)
		)
		(pin "1"
		)
		(instances
			(project "jetson-orin-baseboard-oculink-expansion"
				(path ""
					(reference "TP8")
					(unit 1)
				)
			)
		)
	)
	(symbol
		(lib_id "antmicroCapacitors0402:C_10u_0402")
		(at 242.57 167.64 90)
		(unit 1)
		(exclude_from_sim no)
		(in_bom yes)
		(on_board yes)
		(dnp no)
		(property "Reference" "C33"
			(at 244.348 163.83 90)
			(effects
				(font
					(size 1.27 1.27)
					(thickness 0.15)
				)
				(justify right)
			)
		)
		(property "Value" "C_10u_0402"
			(at 252.73 147.32 0)
			(effects
				(font
					(size 1.27 1.27)
					(thickness 0.15)
				)
				(justify left bottom)
				(hide yes)
			)
		)
		(property "Footprint" "antmicro-footprints:C_0402_1005Metric"
			(at 255.27 147.32 0)
			(effects
				(font
					(size 1.27 1.27)
					(thickness 0.15)
				)
				(justify left bottom)
				(hide yes)
			)
		)
		(property "Datasheet" "https://www.yageo.com/en/Chart/Download/pdf/CC0402MRX5R5BB106"
			(at 257.81 147.32 0)
			(effects
				(font
					(size 1.27 1.27)
					(thickness 0.15)
				)
				(justify left bottom)
				(hide yes)
			)
		)
		(property "Description" "SMD Multilayer Ceramic Capacitor, 10 µF, 6.3 V, 0402 [1005 Metric], ± 20%, X5R, CC Series"
			(at 242.57 167.64 0)
			(effects
				(font
					(size 1.27 1.27)
				)
				(hide yes)
			)
		)
		(property "MPN" "CC0402MRX5R5BB106"
			(at 260.35 147.32 0)
			(effects
				(font
					(size 1.27 1.27)
					(thickness 0.15)
				)
				(justify left bottom)
				(hide yes)
			)
		)
		(property "Manufacturer" "YAGEO"
			(at 262.89 147.32 0)
			(effects
				(font
					(size 1.27 1.27)
					(thickness 0.15)
				)
				(justify left bottom)
				(hide yes)
			)
		)
		(property "License" "Apache-2.0"
			(at 265.43 147.32 0)
			(effects
				(font
					(size 1.27 1.27)
					(thickness 0.15)
				)
				(justify left bottom)
				(hide yes)
			)
		)
		(property "Author" "Antmicro"
			(at 267.97 147.32 0)
			(effects
				(font
					(size 1.27 1.27)
					(thickness 0.15)
				)
				(justify left bottom)
				(hide yes)
			)
		)
		(property "Val" "10u"
			(at 244.348 166.37 90)
			(effects
				(font
					(size 1.27 1.27)
					(thickness 0.15)
				)
				(justify right)
			)
		)
		(property "Voltage" ""
			(at 270.51 147.32 0)
			(effects
				(font
					(size 1.27 1.27)
				)
				(justify left bottom)
				(hide yes)
			)
		)
		(property "Dielectric" ""
			(at 273.05 147.32 0)
			(effects
				(font
					(size 1.27 1.27)
				)
				(justify left bottom)
				(hide yes)
			)
		)
		(pin "1"
		)
		(pin "2"
		)
		(instances
			(project "jetson-orin-baseboard-oculink-expansion"
				(path ""
					(reference "C33")
					(unit 1)
				)
			)
		)
	)
	(symbol
		(lib_id "antmicropower:+3V3")
		(at 231.14 97.79 0)
		(unit 1)
		(exclude_from_sim no)
		(in_bom yes)
		(on_board yes)
		(dnp no)
		(property "Reference" "#PWR055"
			(at 246.38 97.79 0)
			(effects
				(font
					(size 1.27 1.27)
					(thickness 0.15)
				)
				(justify left bottom)
				(hide yes)
			)
		)
		(property "Value" "+3V3"
			(at 234.95 96.52 0)
			(effects
				(font
					(size 1.27 1.27)
					(thickness 0.15)
				)
			)
		)
		(property "Footprint" ""
			(at 246.38 105.41 0)
			(effects
				(font
					(size 1.27 1.27)
					(thickness 0.15)
				)
				(justify left bottom)
				(hide yes)
			)
		)
		(property "Datasheet" ""
			(at 246.38 107.95 0)
			(effects
				(font
					(size 1.27 1.27)
					(thickness 0.15)
				)
				(justify left bottom)
				(hide yes)
			)
		)
		(property "Description" ""
			(at 231.14 97.79 0)
			(effects
				(font
					(size 1.27 1.27)
				)
				(hide yes)
			)
		)
		(property "Author" "Antmicro"
			(at 246.38 100.33 0)
			(effects
				(font
					(size 1.27 1.27)
					(thickness 0.15)
				)
				(justify left bottom)
				(hide yes)
			)
		)
		(property "License" "Apache-2.0"
			(at 246.38 102.87 0)
			(effects
				(font
					(size 1.27 1.27)
					(thickness 0.15)
				)
				(justify left bottom)
				(hide yes)
			)
		)
		(pin "1"
		)
		(instances
			(project "jetson-orin-baseboard-oculink-expansion"
				(path ""
					(reference "#PWR055")
					(unit 1)
				)
			)
		)
	)
	(symbol
		(lib_id "antmicroCapacitors0402:C_100n_0402")
		(at 163.83 187.96 270)
		(mirror x)
		(unit 1)
		(exclude_from_sim no)
		(in_bom yes)
		(on_board yes)
		(dnp no)
		(fields_autoplaced yes)
		(property "Reference" "C12"
			(at 161.29 184.1436 90)
			(effects
				(font
					(size 1.27 1.27)
					(thickness 0.15)
				)
				(justify right)
			)
		)
		(property "Value" "C_100n_0402"
			(at 153.67 167.64 0)
			(effects
				(font
					(size 1.27 1.27)
					(thickness 0.15)
				)
				(justify left bottom)
				(hide yes)
			)
		)
		(property "Footprint" "antmicro-footprints:C_0402_1005Metric"
			(at 151.13 167.64 0)
			(effects
				(font
					(size 1.27 1.27)
					(thickness 0.15)
				)
				(justify left bottom)
				(hide yes)
			)
		)
		(property "Datasheet" "https://www.murata.com/products/productdetail?partno=GRM155R61H104KE14%23"
			(at 148.59 167.64 0)
			(effects
				(font
					(size 1.27 1.27)
					(thickness 0.15)
				)
				(justify left bottom)
				(hide yes)
			)
		)
		(property "Description" "SMD Multilayer Ceramic Capacitor, 0.1 µF, 50 V, 0402 [1005 Metric], ± 10%, X5R, GRM Series"
			(at 163.83 187.96 0)
			(effects
				(font
					(size 1.27 1.27)
				)
				(hide yes)
			)
		)
		(property "MPN" "GRM155R61H104KE14D"
			(at 146.05 167.64 0)
			(effects
				(font
					(size 1.27 1.27)
					(thickness 0.15)
				)
				(justify left bottom)
				(hide yes)
			)
		)
		(property "Manufacturer" "Murata"
			(at 143.51 167.64 0)
			(effects
				(font
					(size 1.27 1.27)
					(thickness 0.15)
				)
				(justify left bottom)
				(hide yes)
			)
		)
		(property "License" "Apache-2.0"
			(at 140.97 167.64 0)
			(effects
				(font
					(size 1.27 1.27)
					(thickness 0.15)
				)
				(justify left bottom)
				(hide yes)
			)
		)
		(property "Author" "Antmicro"
			(at 138.43 167.64 0)
			(effects
				(font
					(size 1.27 1.27)
					(thickness 0.15)
				)
				(justify left bottom)
				(hide yes)
			)
		)
		(property "Val" "100n"
			(at 161.29 186.6836 90)
			(effects
				(font
					(size 1.27 1.27)
					(thickness 0.15)
				)
				(justify right)
			)
		)
		(property "Voltage" "50V"
			(at 135.89 167.64 0)
			(effects
				(font
					(size 1.27 1.27)
				)
				(justify left bottom)
				(hide yes)
			)
		)
		(property "Dielectric" "X5R"
			(at 133.35 167.64 0)
			(effects
				(font
					(size 1.27 1.27)
				)
				(justify left bottom)
				(hide yes)
			)
		)
		(property "Public" "False"
			(at 130.81 167.64 0)
			(effects
				(font
					(size 1.27 1.27)
				)
				(justify left bottom)
				(hide yes)
			)
		)
		(pin "1"
		)
		(pin "2"
		)
		(instances
			(project "jetson-orin-baseboard-oculink-expansion"
				(path ""
					(reference "C12")
					(unit 1)
				)
			)
		)
	)
	(symbol
		(lib_id "antmicropower:GND")
		(at 289.56 132.08 0)
		(mirror y)
		(unit 1)
		(exclude_from_sim no)
		(in_bom yes)
		(on_board yes)
		(dnp no)
		(property "Reference" "#PWR07"
			(at 280.67 134.62 0)
			(effects
				(font
					(size 1.27 1.27)
					(thickness 0.15)
				)
				(justify left bottom)
				(hide yes)
			)
		)
		(property "Value" "GND"
			(at 289.56 135.89 0)
			(effects
				(font
					(size 1.27 1.27)
					(thickness 0.15)
				)
			)
		)
		(property "Footprint" ""
			(at 280.67 139.7 0)
			(effects
				(font
					(size 1.27 1.27)
					(thickness 0.15)
				)
				(justify left bottom)
				(hide yes)
			)
		)
		(property "Datasheet" ""
			(at 280.67 144.78 0)
			(effects
				(font
					(size 1.27 1.27)
					(thickness 0.15)
				)
				(justify left bottom)
				(hide yes)
			)
		)
		(property "Description" ""
			(at 289.56 132.08 0)
			(effects
				(font
					(size 1.27 1.27)
				)
				(hide yes)
			)
		)
		(property "Author" "Antmicro"
			(at 280.67 139.7 0)
			(effects
				(font
					(size 1.27 1.27)
					(thickness 0.15)
				)
				(justify left bottom)
				(hide yes)
			)
		)
		(property "License" "Apache-2.0"
			(at 280.67 142.24 0)
			(effects
				(font
					(size 1.27 1.27)
					(thickness 0.15)
				)
				(justify left bottom)
				(hide yes)
			)
		)
		(pin "1"
		)
		(instances
			(project "jetson-orin-baseboard-oculink-expansion"
				(path ""
					(reference "#PWR07")
					(unit 1)
				)
			)
		)
	)
	(symbol
		(lib_id "antmicropower:+3.3V")
		(at 242.57 160.02 0)
		(mirror y)
		(unit 1)
		(exclude_from_sim no)
		(in_bom yes)
		(on_board yes)
		(dnp no)
		(property "Reference" "#PWR053"
			(at 242.57 163.83 0)
			(effects
				(font
					(size 1.27 1.27)
				)
				(hide yes)
			)
		)
		(property "Value" "+5V"
			(at 242.57 154.94 0)
			(effects
				(font
					(size 1.27 1.27)
				)
			)
		)
		(property "Footprint" ""
			(at 242.57 160.02 0)
			(effects
				(font
					(size 1.27 1.27)
				)
				(hide yes)
			)
		)
		(property "Datasheet" ""
			(at 242.57 160.02 0)
			(effects
				(font
					(size 1.27 1.27)
				)
				(hide yes)
			)
		)
		(property "Description" ""
			(at 242.57 160.02 0)
			(effects
				(font
					(size 1.27 1.27)
				)
				(hide yes)
			)
		)
		(pin "1"
		)
		(instances
			(project "jetson-orin-baseboard-oculink-expansion"
				(path ""
					(reference "#PWR053")
					(unit 1)
				)
			)
		)
	)
	(symbol
		(lib_id "antmicroTestPoints:TP_0.75mm_SMD")
		(at 224.79 240.03 0)
		(unit 1)
		(exclude_from_sim no)
		(in_bom no)
		(on_board yes)
		(dnp no)
		(property "Reference" "TP11"
			(at 231.14 240.03 0)
			(effects
				(font
					(size 1.27 1.27)
					(thickness 0.15)
				)
			)
		)
		(property "Value" "TP_0.75mm_SMD"
			(at 235.585 243.84 0)
			(effects
				(font
					(size 1.27 1.27)
					(thickness 0.15)
				)
				(justify left bottom)
				(hide yes)
			)
		)
		(property "Footprint" "antmicro-footprints:TP_SMD_0.75mm"
			(at 235.585 246.38 0)
			(effects
				(font
					(size 1.27 1.27)
					(thickness 0.15)
				)
				(justify left bottom)
				(hide yes)
			)
		)
		(property "Datasheet" ""
			(at 242.57 252.73 0)
			(effects
				(font
					(size 1.27 1.27)
					(thickness 0.15)
				)
				(justify left bottom)
				(hide yes)
			)
		)
		(property "Description" "SMT test point"
			(at 224.79 240.03 0)
			(effects
				(font
					(size 1.27 1.27)
				)
				(hide yes)
			)
		)
		(property "MPN" ""
			(at 235.585 251.46 0)
			(effects
				(font
					(size 1.27 1.27)
					(thickness 0.15)
				)
				(justify left bottom)
				(hide yes)
			)
		)
		(property "Manufacturer" ""
			(at 235.585 246.38 0)
			(effects
				(font
					(size 1.27 1.27)
					(thickness 0.15)
				)
				(justify left bottom)
				(hide yes)
			)
		)
		(property "Author" "Antmicro"
			(at 235.585 248.92 0)
			(effects
				(font
					(size 1.27 1.27)
					(thickness 0.15)
				)
				(justify left bottom)
				(hide yes)
			)
		)
		(property "License" "Apache-2.0"
			(at 235.585 251.46 0)
			(effects
				(font
					(size 1.27 1.27)
					(thickness 0.15)
				)
				(justify left bottom)
				(hide yes)
			)
		)
		(property "Public" "False"
			(at 234.95 254 0)
			(effects
				(font
					(size 1.27 1.27)
				)
				(justify left bottom)
				(hide yes)
			)
		)
		(pin "1"
		)
		(instances
			(project "jetson-orin-baseboard-oculink-expansion"
				(path ""
					(reference "TP11")
					(unit 1)
				)
			)
		)
	)
	(symbol
		(lib_id "antmicroCapacitors0402:C_220n_0402")
		(at 172.72 201.93 0)
		(unit 1)
		(exclude_from_sim no)
		(in_bom yes)
		(on_board yes)
		(dnp no)
		(property "Reference" "C41"
			(at 171.45 200.66 0)
			(effects
				(font
					(size 1.27 1.27)
					(thickness 0.15)
				)
			)
		)
		(property "Value" "C_220n_0402"
			(at 193.04 212.09 0)
			(effects
				(font
					(size 1.27 1.27)
					(thickness 0.15)
				)
				(justify left bottom)
				(hide yes)
			)
		)
		(property "Footprint" "antmicro-footprints:C_0402_1005Metric"
			(at 193.04 214.63 0)
			(effects
				(font
					(size 1.27 1.27)
					(thickness 0.15)
				)
				(justify left bottom)
				(hide yes)
			)
		)
		(property "Datasheet" "https://www.yageo.com/en/Chart/Download/pdf/CC0402KRX5R6BB224"
			(at 193.04 217.17 0)
			(effects
				(font
					(size 1.27 1.27)
					(thickness 0.15)
				)
				(justify left bottom)
				(hide yes)
			)
		)
		(property "Description" "SMD Multilayer Ceramic Capacitor, 0.22 µF, 10 V, 0402 [1005 Metric], ± 10%, X5R, CC Series"
			(at 172.72 201.93 0)
			(effects
				(font
					(size 1.27 1.27)
				)
				(hide yes)
			)
		)
		(property "MPN" "CC0402KRX5R6BB224"
			(at 193.04 219.71 0)
			(effects
				(font
					(size 1.27 1.27)
					(thickness 0.15)
				)
				(justify left bottom)
				(hide yes)
			)
		)
		(property "Manufacturer" "YAGEO"
			(at 193.04 222.25 0)
			(effects
				(font
					(size 1.27 1.27)
					(thickness 0.15)
				)
				(justify left bottom)
				(hide yes)
			)
		)
		(property "License" "Apache-2.0"
			(at 193.04 224.79 0)
			(effects
				(font
					(size 1.27 1.27)
					(thickness 0.15)
				)
				(justify left bottom)
				(hide yes)
			)
		)
		(property "Author" "Antmicro"
			(at 193.04 227.33 0)
			(effects
				(font
					(size 1.27 1.27)
					(thickness 0.15)
				)
				(justify left bottom)
				(hide yes)
			)
		)
		(property "Val" "220n"
			(at 179.07 200.66 0)
			(effects
				(font
					(size 1.27 1.27)
					(thickness 0.15)
				)
			)
		)
		(property "Voltage" ""
			(at 193.04 229.87 0)
			(effects
				(font
					(size 1.27 1.27)
				)
				(justify left bottom)
				(hide yes)
			)
		)
		(property "Dielectric" ""
			(at 193.04 232.41 0)
			(effects
				(font
					(size 1.27 1.27)
				)
				(justify left bottom)
				(hide yes)
			)
		)
		(property "Public" "False"
			(at 193.04 234.95 0)
			(effects
				(font
					(size 1.27 1.27)
				)
				(justify left bottom)
				(hide yes)
			)
		)
		(pin "1"
		)
		(pin "2"
		)
		(instances
			(project "jetson-orin-baseboard-oculink-expansion"
				(path ""
					(reference "C41")
					(unit 1)
				)
			)
		)
	)
	(symbol
		(lib_id "antmicropower:+1V8")
		(at 328.93 187.96 0)
		(unit 1)
		(exclude_from_sim no)
		(in_bom yes)
		(on_board yes)
		(dnp no)
		(fields_autoplaced yes)
		(property "Reference" "#PWR014"
			(at 344.17 190.5 0)
			(effects
				(font
					(size 1.27 1.27)
					(thickness 0.15)
				)
				(justify left bottom)
				(hide yes)
			)
		)
		(property "Value" "+1V8"
			(at 328.93 182.88 0)
			(effects
				(font
					(size 1.27 1.27)
					(thickness 0.15)
				)
			)
		)
		(property "Footprint" ""
			(at 344.17 195.58 0)
			(effects
				(font
					(size 1.27 1.27)
					(thickness 0.15)
				)
				(justify left bottom)
				(hide yes)
			)
		)
		(property "Datasheet" ""
			(at 344.17 198.12 0)
			(effects
				(font
					(size 1.27 1.27)
					(thickness 0.15)
				)
				(justify left bottom)
				(hide yes)
			)
		)
		(property "Description" ""
			(at 328.93 187.96 0)
			(effects
				(font
					(size 1.27 1.27)
				)
				(hide yes)
			)
		)
		(property "Author" "Antmicro"
			(at 344.17 193.04 0)
			(effects
				(font
					(size 1.27 1.27)
					(thickness 0.15)
				)
				(justify left bottom)
				(hide yes)
			)
		)
		(property "License" "Apache-2.0"
			(at 344.17 195.58 0)
			(effects
				(font
					(size 1.27 1.27)
					(thickness 0.15)
				)
				(justify left bottom)
				(hide yes)
			)
		)
		(pin "1"
		)
		(instances
			(project "jetson-orin-baseboard-oculink-expansion"
				(path ""
					(reference "#PWR014")
					(unit 1)
				)
			)
		)
	)
	(symbol
		(lib_id "antmicroCapacitors0402:C_10u_0402")
		(at 358.14 163.83 90)
		(unit 1)
		(exclude_from_sim no)
		(in_bom yes)
		(on_board yes)
		(dnp no)
		(fields_autoplaced yes)
		(property "Reference" "C2"
			(at 360.68 160.0136 90)
			(effects
				(font
					(size 1.27 1.27)
					(thickness 0.15)
				)
				(justify right)
			)
		)
		(property "Value" "C_10u_0402"
			(at 368.3 143.51 0)
			(effects
				(font
					(size 1.27 1.27)
					(thickness 0.15)
				)
				(justify left bottom)
				(hide yes)
			)
		)
		(property "Footprint" "antmicro-footprints:C_0402_1005Metric"
			(at 370.84 143.51 0)
			(effects
				(font
					(size 1.27 1.27)
					(thickness 0.15)
				)
				(justify left bottom)
				(hide yes)
			)
		)
		(property "Datasheet" "https://www.yageo.com/en/Chart/Download/pdf/CC0402MRX5R5BB106"
			(at 373.38 143.51 0)
			(effects
				(font
					(size 1.27 1.27)
					(thickness 0.15)
				)
				(justify left bottom)
				(hide yes)
			)
		)
		(property "Description" "SMD Multilayer Ceramic Capacitor, 10 µF, 6.3 V, 0402 [1005 Metric], ± 20%, X5R, CC Series"
			(at 358.14 163.83 0)
			(effects
				(font
					(size 1.27 1.27)
				)
				(hide yes)
			)
		)
		(property "MPN" "CC0402MRX5R5BB106"
			(at 375.92 143.51 0)
			(effects
				(font
					(size 1.27 1.27)
					(thickness 0.15)
				)
				(justify left bottom)
				(hide yes)
			)
		)
		(property "Manufacturer" "YAGEO"
			(at 378.46 143.51 0)
			(effects
				(font
					(size 1.27 1.27)
					(thickness 0.15)
				)
				(justify left bottom)
				(hide yes)
			)
		)
		(property "License" "Apache-2.0"
			(at 381 143.51 0)
			(effects
				(font
					(size 1.27 1.27)
					(thickness 0.15)
				)
				(justify left bottom)
				(hide yes)
			)
		)
		(property "Author" "Antmicro"
			(at 383.54 143.51 0)
			(effects
				(font
					(size 1.27 1.27)
					(thickness 0.15)
				)
				(justify left bottom)
				(hide yes)
			)
		)
		(property "Val" "10u"
			(at 360.68 162.5536 90)
			(effects
				(font
					(size 1.27 1.27)
					(thickness 0.15)
				)
				(justify right)
			)
		)
		(property "Voltage" ""
			(at 386.08 143.51 0)
			(effects
				(font
					(size 1.27 1.27)
				)
				(justify left bottom)
				(hide yes)
			)
		)
		(property "Dielectric" ""
			(at 388.62 143.51 0)
			(effects
				(font
					(size 1.27 1.27)
				)
				(justify left bottom)
				(hide yes)
			)
		)
		(pin "1"
		)
		(pin "2"
		)
		(instances
			(project "jetson-orin-baseboard-oculink-expansion"
				(path ""
					(reference "C2")
					(unit 1)
				)
			)
		)
	)
	(symbol
		(lib_id "antmicropower:GND")
		(at 358.14 168.91 0)
		(unit 1)
		(exclude_from_sim no)
		(in_bom yes)
		(on_board yes)
		(dnp no)
		(fields_autoplaced yes)
		(property "Reference" "#PWR08"
			(at 358.14 175.26 0)
			(effects
				(font
					(size 1.27 1.27)
				)
				(justify left bottom)
				(hide yes)
			)
		)
		(property "Value" "GND"
			(at 358.14 172.72 0)
			(effects
				(font
					(size 1.27 1.27)
					(thickness 0.15)
				)
			)
		)
		(property "Footprint" ""
			(at 367.03 176.53 0)
			(effects
				(font
					(size 1.27 1.27)
					(thickness 0.15)
				)
				(justify left bottom)
				(hide yes)
			)
		)
		(property "Datasheet" ""
			(at 367.03 181.61 0)
			(effects
				(font
					(size 1.27 1.27)
					(thickness 0.15)
				)
				(justify left bottom)
				(hide yes)
			)
		)
		(property "Description" ""
			(at 358.14 168.91 0)
			(effects
				(font
					(size 1.27 1.27)
				)
				(hide yes)
			)
		)
		(property "Author" "Antmicro"
			(at 367.03 176.53 0)
			(effects
				(font
					(size 1.27 1.27)
					(thickness 0.15)
				)
				(justify left bottom)
				(hide yes)
			)
		)
		(property "License" "Apache-2.0"
			(at 367.03 179.07 0)
			(effects
				(font
					(size 1.27 1.27)
					(thickness 0.15)
				)
				(justify left bottom)
				(hide yes)
			)
		)
		(pin "1"
		)
		(instances
			(project "jetson-orin-baseboard-oculink-expansion"
				(path ""
					(reference "#PWR08")
					(unit 1)
				)
			)
		)
	)
	(symbol
		(lib_id "antmicroCapacitors0402:C_100n_0402")
		(at 386.08 196.85 90)
		(unit 1)
		(exclude_from_sim no)
		(in_bom yes)
		(on_board yes)
		(dnp no)
		(fields_autoplaced yes)
		(property "Reference" "C5"
			(at 388.62 193.0336 90)
			(effects
				(font
					(size 1.27 1.27)
					(thickness 0.15)
				)
				(justify right)
			)
		)
		(property "Value" "C_100n_0402"
			(at 396.24 176.53 0)
			(effects
				(font
					(size 1.27 1.27)
					(thickness 0.15)
				)
				(justify left bottom)
				(hide yes)
			)
		)
		(property "Footprint" "antmicro-footprints:C_0402_1005Metric"
			(at 398.78 176.53 0)
			(effects
				(font
					(size 1.27 1.27)
					(thickness 0.15)
				)
				(justify left bottom)
				(hide yes)
			)
		)
		(property "Datasheet" "https://www.murata.com/products/productdetail?partno=GRM155R61H104KE14%23"
			(at 401.32 176.53 0)
			(effects
				(font
					(size 1.27 1.27)
					(thickness 0.15)
				)
				(justify left bottom)
				(hide yes)
			)
		)
		(property "Description" "SMD Multilayer Ceramic Capacitor, 0.1 µF, 50 V, 0402 [1005 Metric], ± 10%, X5R, GRM Series"
			(at 386.08 196.85 0)
			(effects
				(font
					(size 1.27 1.27)
				)
				(hide yes)
			)
		)
		(property "MPN" "GRM155R61H104KE14D"
			(at 403.86 176.53 0)
			(effects
				(font
					(size 1.27 1.27)
					(thickness 0.15)
				)
				(justify left bottom)
				(hide yes)
			)
		)
		(property "Manufacturer" "Murata"
			(at 406.4 176.53 0)
			(effects
				(font
					(size 1.27 1.27)
					(thickness 0.15)
				)
				(justify left bottom)
				(hide yes)
			)
		)
		(property "License" "Apache-2.0"
			(at 408.94 176.53 0)
			(effects
				(font
					(size 1.27 1.27)
					(thickness 0.15)
				)
				(justify left bottom)
				(hide yes)
			)
		)
		(property "Author" "Antmicro"
			(at 411.48 176.53 0)
			(effects
				(font
					(size 1.27 1.27)
					(thickness 0.15)
				)
				(justify left bottom)
				(hide yes)
			)
		)
		(property "Val" "100n"
			(at 388.62 195.5736 90)
			(effects
				(font
					(size 1.27 1.27)
					(thickness 0.15)
				)
				(justify right)
			)
		)
		(property "Voltage" "50V"
			(at 414.02 176.53 0)
			(effects
				(font
					(size 1.27 1.27)
				)
				(justify left bottom)
				(hide yes)
			)
		)
		(property "Dielectric" "X5R"
			(at 416.56 176.53 0)
			(effects
				(font
					(size 1.27 1.27)
				)
				(justify left bottom)
				(hide yes)
			)
		)
		(pin "1"
		)
		(pin "2"
		)
		(instances
			(project ""
				(path ""
					(reference "C5")
					(unit 1)
				)
			)
		)
	)
	(symbol
		(lib_id "antmicroLogicTranslatorsLevelShifters:MAX3373EEKA+")
		(at 360.68 190.5 0)
		(mirror y)
		(unit 1)
		(exclude_from_sim no)
		(in_bom yes)
		(on_board yes)
		(dnp no)
		(property "Reference" "U1"
			(at 346.71 182.88 0)
			(effects
				(font
					(size 1.27 1.27)
					(thickness 0.15)
				)
			)
		)
		(property "Value" "MAX3373EEKA+"
			(at 317.5 198.12 0)
			(effects
				(font
					(size 1.27 1.27)
					(thickness 0.15)
				)
				(justify left bottom)
				(hide yes)
			)
		)
		(property "Footprint" "antmicro-footprints:SOT-23-8"
			(at 317.5 200.66 0)
			(effects
				(font
					(size 1.27 1.27)
					(thickness 0.15)
				)
				(justify left bottom)
				(hide yes)
			)
		)
		(property "Datasheet" "https://www.analog.com/en/products/max3373e.html"
			(at 317.5 203.2 0)
			(effects
				(font
					(size 1.27 1.27)
					(thickness 0.15)
				)
				(justify left bottom)
				(hide yes)
			)
		)
		(property "Description" "±15kV ESD-Protected, 1µA, 16Mbps, Dual/Quad Low-Voltage Level Translators in UCSP"
			(at 360.68 190.5 0)
			(effects
				(font
					(size 1.27 1.27)
				)
				(hide yes)
			)
		)
		(property "MPN" "MAX3373EEKA+"
			(at 346.71 185.42 0)
			(effects
				(font
					(size 1.27 1.27)
					(thickness 0.15)
				)
			)
		)
		(property "Manufacturer" "Analog Devices"
			(at 317.5 205.74 0)
			(effects
				(font
					(size 1.27 1.27)
					(thickness 0.15)
				)
				(justify left bottom)
				(hide yes)
			)
		)
		(property "Author" "Antmicro"
			(at 317.5 208.28 0)
			(effects
				(font
					(size 1.27 1.27)
					(thickness 0.15)
				)
				(justify left bottom)
				(hide yes)
			)
		)
		(property "License" "Apache-2.0"
			(at 317.5 210.82 0)
			(effects
				(font
					(size 1.27 1.27)
					(thickness 0.15)
				)
				(justify left bottom)
				(hide yes)
			)
		)
		(pin "8"
		)
		(pin "3"
		)
		(pin "6"
		)
		(pin "7"
		)
		(pin "1"
		)
		(pin "2"
		)
		(pin "4"
		)
		(pin "5"
		)
		(instances
			(project ""
				(path ""
					(reference "U1")
					(unit 1)
				)
			)
		)
	)
	(symbol
		(lib_id "antmicroCapacitors0402:C_220n_0402")
		(at 245.11 73.66 0)
		(unit 1)
		(exclude_from_sim no)
		(in_bom yes)
		(on_board yes)
		(dnp no)
		(property "Reference" "C15"
			(at 243.84 74.93 0)
			(effects
				(font
					(size 1.27 1.27)
					(thickness 0.15)
				)
			)
		)
		(property "Value" "C_220n_0402"
			(at 265.43 83.82 0)
			(effects
				(font
					(size 1.27 1.27)
					(thickness 0.15)
				)
				(justify left bottom)
				(hide yes)
			)
		)
		(property "Footprint" "antmicro-footprints:C_0402_1005Metric"
			(at 265.43 86.36 0)
			(effects
				(font
					(size 1.27 1.27)
					(thickness 0.15)
				)
				(justify left bottom)
				(hide yes)
			)
		)
		(property "Datasheet" "https://www.yageo.com/en/Chart/Download/pdf/CC0402KRX5R6BB224"
			(at 265.43 88.9 0)
			(effects
				(font
					(size 1.27 1.27)
					(thickness 0.15)
				)
				(justify left bottom)
				(hide yes)
			)
		)
		(property "Description" "SMD Multilayer Ceramic Capacitor, 0.22 µF, 10 V, 0402 [1005 Metric], ± 10%, X5R, CC Series"
			(at 245.11 73.66 0)
			(effects
				(font
					(size 1.27 1.27)
				)
				(hide yes)
			)
		)
		(property "MPN" "CC0402KRX5R6BB224"
			(at 265.43 91.44 0)
			(effects
				(font
					(size 1.27 1.27)
					(thickness 0.15)
				)
				(justify left bottom)
				(hide yes)
			)
		)
		(property "Manufacturer" "YAGEO"
			(at 265.43 93.98 0)
			(effects
				(font
					(size 1.27 1.27)
					(thickness 0.15)
				)
				(justify left bottom)
				(hide yes)
			)
		)
		(property "License" "Apache-2.0"
			(at 265.43 96.52 0)
			(effects
				(font
					(size 1.27 1.27)
					(thickness 0.15)
				)
				(justify left bottom)
				(hide yes)
			)
		)
		(property "Author" "Antmicro"
			(at 265.43 99.06 0)
			(effects
				(font
					(size 1.27 1.27)
					(thickness 0.15)
				)
				(justify left bottom)
				(hide yes)
			)
		)
		(property "Val" "220n"
			(at 251.46 74.93 0)
			(effects
				(font
					(size 1.27 1.27)
					(thickness 0.15)
				)
			)
		)
		(property "Voltage" ""
			(at 265.43 101.6 0)
			(effects
				(font
					(size 1.27 1.27)
				)
				(justify left bottom)
				(hide yes)
			)
		)
		(property "Dielectric" ""
			(at 265.43 104.14 0)
			(effects
				(font
					(size 1.27 1.27)
				)
				(justify left bottom)
				(hide yes)
			)
		)
		(property "Public" "False"
			(at 265.43 106.68 0)
			(effects
				(font
					(size 1.27 1.27)
				)
				(justify left bottom)
				(hide yes)
			)
		)
		(pin "1"
		)
		(pin "2"
		)
		(instances
			(project "jetson-orin-baseboard-oculink-expansion"
				(path ""
					(reference "C15")
					(unit 1)
				)
			)
		)
	)
	(symbol
		(lib_id "antmicropower:GND")
		(at 182.88 34.29 0)
		(unit 1)
		(exclude_from_sim no)
		(in_bom yes)
		(on_board yes)
		(dnp no)
		(property "Reference" "#PWR049"
			(at 191.77 36.83 0)
			(effects
				(font
					(size 1.27 1.27)
					(thickness 0.15)
				)
				(justify left bottom)
				(hide yes)
			)
		)
		(property "Value" "GND"
			(at 182.88 38.1 0)
			(effects
				(font
					(size 1.27 1.27)
					(thickness 0.15)
				)
			)
		)
		(property "Footprint" ""
			(at 191.77 41.91 0)
			(effects
				(font
					(size 1.27 1.27)
					(thickness 0.15)
				)
				(justify left bottom)
				(hide yes)
			)
		)
		(property "Datasheet" ""
			(at 191.77 46.99 0)
			(effects
				(font
					(size 1.27 1.27)
					(thickness 0.15)
				)
				(justify left bottom)
				(hide yes)
			)
		)
		(property "Description" ""
			(at 182.88 34.29 0)
			(effects
				(font
					(size 1.27 1.27)
				)
				(hide yes)
			)
		)
		(property "Author" "Antmicro"
			(at 191.77 41.91 0)
			(effects
				(font
					(size 1.27 1.27)
					(thickness 0.15)
				)
				(justify left bottom)
				(hide yes)
			)
		)
		(property "License" "Apache-2.0"
			(at 191.77 44.45 0)
			(effects
				(font
					(size 1.27 1.27)
					(thickness 0.15)
				)
				(justify left bottom)
				(hide yes)
			)
		)
		(pin "1"
		)
		(instances
			(project "jetson-orin-baseboard-oculink-expansion"
				(path ""
					(reference "#PWR049")
					(unit 1)
				)
			)
		)
	)
	(symbol
		(lib_id "antmicroTestPoints:TP_1.5mm_SMD")
		(at 43.18 71.12 180)
		(unit 1)
		(exclude_from_sim no)
		(in_bom no)
		(on_board yes)
		(dnp no)
		(property "Reference" "TP5"
			(at 37.338 71.12 0)
			(effects
				(font
					(size 1.27 1.27)
					(thickness 0.15)
				)
			)
		)
		(property "Value" "TP_1.5mm_SMD"
			(at 27.94 63.5 0)
			(effects
				(font
					(size 1.27 1.27)
					(thickness 0.15)
				)
				(justify left bottom)
				(hide yes)
			)
		)
		(property "Footprint" "antmicro-footprints:TP_SMD_1.5mm"
			(at 27.94 60.96 0)
			(effects
				(font
					(size 1.27 1.27)
					(thickness 0.15)
				)
				(justify left bottom)
				(hide yes)
			)
		)
		(property "Datasheet" ""
			(at 25.4 58.42 0)
			(effects
				(font
					(size 1.27 1.27)
					(thickness 0.15)
				)
				(justify left bottom)
				(hide yes)
			)
		)
		(property "Description" "test point, SMT"
			(at 43.18 71.12 0)
			(effects
				(font
					(size 1.27 1.27)
				)
				(hide yes)
			)
		)
		(property "MPN" ""
			(at 43.18 71.12 0)
			(effects
				(font
					(size 1.27 1.27)
				)
				(hide yes)
			)
		)
		(property "Manufacturer" ""
			(at 43.18 71.12 0)
			(effects
				(font
					(size 1.27 1.27)
				)
				(hide yes)
			)
		)
		(property "Author" "Antmicro"
			(at 27.94 55.88 0)
			(effects
				(font
					(size 1.27 1.27)
					(thickness 0.15)
				)
				(justify left bottom)
				(hide yes)
			)
		)
		(property "License" "Apache-2.0"
			(at 27.94 53.34 0)
			(effects
				(font
					(size 1.27 1.27)
					(thickness 0.15)
				)
				(justify left bottom)
				(hide yes)
			)
		)
		(pin "1"
		)
		(instances
			(project "jetson-orin-baseboard-oculink-expansion"
				(path ""
					(reference "TP5")
					(unit 1)
				)
			)
		)
	)
	(symbol
		(lib_id "antmicroTestPoints:TP_0.75mm_SMD")
		(at 233.68 228.6 0)
		(mirror x)
		(unit 1)
		(exclude_from_sim no)
		(in_bom no)
		(on_board yes)
		(dnp no)
		(property "Reference" "TP18"
			(at 240.03 228.6 0)
			(effects
				(font
					(size 1.27 1.27)
					(thickness 0.15)
				)
			)
		)
		(property "Value" "TP_0.75mm_SMD"
			(at 244.475 224.79 0)
			(effects
				(font
					(size 1.27 1.27)
					(thickness 0.15)
				)
				(justify left bottom)
				(hide yes)
			)
		)
		(property "Footprint" "antmicro-footprints:TP_SMD_0.75mm"
			(at 244.475 222.25 0)
			(effects
				(font
					(size 1.27 1.27)
					(thickness 0.15)
				)
				(justify left bottom)
				(hide yes)
			)
		)
		(property "Datasheet" ""
			(at 251.46 215.9 0)
			(effects
				(font
					(size 1.27 1.27)
					(thickness 0.15)
				)
				(justify left bottom)
				(hide yes)
			)
		)
		(property "Description" "SMT test point"
			(at 233.68 228.6 0)
			(effects
				(font
					(size 1.27 1.27)
				)
				(hide yes)
			)
		)
		(property "MPN" ""
			(at 244.475 217.17 0)
			(effects
				(font
					(size 1.27 1.27)
					(thickness 0.15)
				)
				(justify left bottom)
				(hide yes)
			)
		)
		(property "Manufacturer" ""
			(at 244.475 222.25 0)
			(effects
				(font
					(size 1.27 1.27)
					(thickness 0.15)
				)
				(justify left bottom)
				(hide yes)
			)
		)
		(property "Author" "Antmicro"
			(at 244.475 219.71 0)
			(effects
				(font
					(size 1.27 1.27)
					(thickness 0.15)
				)
				(justify left bottom)
				(hide yes)
			)
		)
		(property "License" "Apache-2.0"
			(at 244.475 217.17 0)
			(effects
				(font
					(size 1.27 1.27)
					(thickness 0.15)
				)
				(justify left bottom)
				(hide yes)
			)
		)
		(property "Public" "False"
			(at 243.84 214.63 0)
			(effects
				(font
					(size 1.27 1.27)
				)
				(justify left bottom)
				(hide yes)
			)
		)
		(pin "1"
		)
		(instances
			(project "jetson-orin-baseboard-oculink-expansion"
				(path ""
					(reference "TP18")
					(unit 1)
				)
			)
		)
	)
	(symbol
		(lib_id "antmicroCapacitors0402:C_100n_0402")
		(at 182.88 49.53 90)
		(unit 1)
		(exclude_from_sim no)
		(in_bom yes)
		(on_board yes)
		(dnp no)
		(fields_autoplaced yes)
		(property "Reference" "C30"
			(at 185.42 45.7136 90)
			(effects
				(font
					(size 1.27 1.27)
					(thickness 0.15)
				)
				(justify right)
			)
		)
		(property "Value" "C_100n_0402"
			(at 193.04 29.21 0)
			(effects
				(font
					(size 1.27 1.27)
					(thickness 0.15)
				)
				(justify left bottom)
				(hide yes)
			)
		)
		(property "Footprint" "antmicro-footprints:C_0402_1005Metric"
			(at 195.58 29.21 0)
			(effects
				(font
					(size 1.27 1.27)
					(thickness 0.15)
				)
				(justify left bottom)
				(hide yes)
			)
		)
		(property "Datasheet" "https://www.murata.com/products/productdetail?partno=GRM155R61H104KE14%23"
			(at 198.12 29.21 0)
			(effects
				(font
					(size 1.27 1.27)
					(thickness 0.15)
				)
				(justify left bottom)
				(hide yes)
			)
		)
		(property "Description" "SMD Multilayer Ceramic Capacitor, 0.1 µF, 50 V, 0402 [1005 Metric], ± 10%, X5R, GRM Series"
			(at 182.88 49.53 0)
			(effects
				(font
					(size 1.27 1.27)
				)
				(hide yes)
			)
		)
		(property "MPN" "GRM155R61H104KE14D"
			(at 200.66 29.21 0)
			(effects
				(font
					(size 1.27 1.27)
					(thickness 0.15)
				)
				(justify left bottom)
				(hide yes)
			)
		)
		(property "Manufacturer" "Murata"
			(at 203.2 29.21 0)
			(effects
				(font
					(size 1.27 1.27)
					(thickness 0.15)
				)
				(justify left bottom)
				(hide yes)
			)
		)
		(property "License" "Apache-2.0"
			(at 205.74 29.21 0)
			(effects
				(font
					(size 1.27 1.27)
					(thickness 0.15)
				)
				(justify left bottom)
				(hide yes)
			)
		)
		(property "Author" "Antmicro"
			(at 208.28 29.21 0)
			(effects
				(font
					(size 1.27 1.27)
					(thickness 0.15)
				)
				(justify left bottom)
				(hide yes)
			)
		)
		(property "Val" "100n"
			(at 185.42 48.2536 90)
			(effects
				(font
					(size 1.27 1.27)
					(thickness 0.15)
				)
				(justify right)
			)
		)
		(property "Voltage" "50V"
			(at 210.82 29.21 0)
			(effects
				(font
					(size 1.27 1.27)
				)
				(justify left bottom)
				(hide yes)
			)
		)
		(property "Dielectric" "X5R"
			(at 213.36 29.21 0)
			(effects
				(font
					(size 1.27 1.27)
				)
				(justify left bottom)
				(hide yes)
			)
		)
		(property "Public" "False"
			(at 215.9 29.21 0)
			(effects
				(font
					(size 1.27 1.27)
				)
				(justify left bottom)
				(hide yes)
			)
		)
		(pin "1"
		)
		(pin "2"
		)
		(instances
			(project "jetson-orin-baseboard-oculink-expansion"
				(path ""
					(reference "C30")
					(unit 1)
				)
			)
		)
	)
	(symbol
		(lib_id "antmicroCapacitors0402:C_100n_0402")
		(at 156.21 49.53 90)
		(unit 1)
		(exclude_from_sim no)
		(in_bom yes)
		(on_board yes)
		(dnp no)
		(fields_autoplaced yes)
		(property "Reference" "C20"
			(at 158.75 45.7136 90)
			(effects
				(font
					(size 1.27 1.27)
					(thickness 0.15)
				)
				(justify right)
			)
		)
		(property "Value" "C_100n_0402"
			(at 166.37 29.21 0)
			(effects
				(font
					(size 1.27 1.27)
					(thickness 0.15)
				)
				(justify left bottom)
				(hide yes)
			)
		)
		(property "Footprint" "antmicro-footprints:C_0402_1005Metric"
			(at 168.91 29.21 0)
			(effects
				(font
					(size 1.27 1.27)
					(thickness 0.15)
				)
				(justify left bottom)
				(hide yes)
			)
		)
		(property "Datasheet" "https://www.murata.com/products/productdetail?partno=GRM155R61H104KE14%23"
			(at 171.45 29.21 0)
			(effects
				(font
					(size 1.27 1.27)
					(thickness 0.15)
				)
				(justify left bottom)
				(hide yes)
			)
		)
		(property "Description" "SMD Multilayer Ceramic Capacitor, 0.1 µF, 50 V, 0402 [1005 Metric], ± 10%, X5R, GRM Series"
			(at 156.21 49.53 0)
			(effects
				(font
					(size 1.27 1.27)
				)
				(hide yes)
			)
		)
		(property "MPN" "GRM155R61H104KE14D"
			(at 173.99 29.21 0)
			(effects
				(font
					(size 1.27 1.27)
					(thickness 0.15)
				)
				(justify left bottom)
				(hide yes)
			)
		)
		(property "Manufacturer" "Murata"
			(at 176.53 29.21 0)
			(effects
				(font
					(size 1.27 1.27)
					(thickness 0.15)
				)
				(justify left bottom)
				(hide yes)
			)
		)
		(property "License" "Apache-2.0"
			(at 179.07 29.21 0)
			(effects
				(font
					(size 1.27 1.27)
					(thickness 0.15)
				)
				(justify left bottom)
				(hide yes)
			)
		)
		(property "Author" "Antmicro"
			(at 181.61 29.21 0)
			(effects
				(font
					(size 1.27 1.27)
					(thickness 0.15)
				)
				(justify left bottom)
				(hide yes)
			)
		)
		(property "Val" "100n"
			(at 158.75 48.2536 90)
			(effects
				(font
					(size 1.27 1.27)
					(thickness 0.15)
				)
				(justify right)
			)
		)
		(property "Voltage" "50V"
			(at 184.15 29.21 0)
			(effects
				(font
					(size 1.27 1.27)
				)
				(justify left bottom)
				(hide yes)
			)
		)
		(property "Dielectric" "X5R"
			(at 186.69 29.21 0)
			(effects
				(font
					(size 1.27 1.27)
				)
				(justify left bottom)
				(hide yes)
			)
		)
		(property "Public" "False"
			(at 189.23 29.21 0)
			(effects
				(font
					(size 1.27 1.27)
				)
				(justify left bottom)
				(hide yes)
			)
		)
		(pin "1"
		)
		(pin "2"
		)
		(instances
			(project "jetson-orin-baseboard-oculink-expansion"
				(path ""
					(reference "C20")
					(unit 1)
				)
			)
		)
	)
	(symbol
		(lib_id "antmicroCapacitors0402:C_100n_0402")
		(at 181.61 187.96 270)
		(mirror x)
		(unit 1)
		(exclude_from_sim no)
		(in_bom yes)
		(on_board yes)
		(dnp no)
		(fields_autoplaced yes)
		(property "Reference" "C8"
			(at 179.07 184.1436 90)
			(effects
				(font
					(size 1.27 1.27)
					(thickness 0.15)
				)
				(justify right)
			)
		)
		(property "Value" "C_100n_0402"
			(at 171.45 167.64 0)
			(effects
				(font
					(size 1.27 1.27)
					(thickness 0.15)
				)
				(justify left bottom)
				(hide yes)
			)
		)
		(property "Footprint" "antmicro-footprints:C_0402_1005Metric"
			(at 168.91 167.64 0)
			(effects
				(font
					(size 1.27 1.27)
					(thickness 0.15)
				)
				(justify left bottom)
				(hide yes)
			)
		)
		(property "Datasheet" "https://www.murata.com/products/productdetail?partno=GRM155R61H104KE14%23"
			(at 166.37 167.64 0)
			(effects
				(font
					(size 1.27 1.27)
					(thickness 0.15)
				)
				(justify left bottom)
				(hide yes)
			)
		)
		(property "Description" "SMD Multilayer Ceramic Capacitor, 0.1 µF, 50 V, 0402 [1005 Metric], ± 10%, X5R, GRM Series"
			(at 181.61 187.96 0)
			(effects
				(font
					(size 1.27 1.27)
				)
				(hide yes)
			)
		)
		(property "MPN" "GRM155R61H104KE14D"
			(at 163.83 167.64 0)
			(effects
				(font
					(size 1.27 1.27)
					(thickness 0.15)
				)
				(justify left bottom)
				(hide yes)
			)
		)
		(property "Manufacturer" "Murata"
			(at 161.29 167.64 0)
			(effects
				(font
					(size 1.27 1.27)
					(thickness 0.15)
				)
				(justify left bottom)
				(hide yes)
			)
		)
		(property "License" "Apache-2.0"
			(at 158.75 167.64 0)
			(effects
				(font
					(size 1.27 1.27)
					(thickness 0.15)
				)
				(justify left bottom)
				(hide yes)
			)
		)
		(property "Author" "Antmicro"
			(at 156.21 167.64 0)
			(effects
				(font
					(size 1.27 1.27)
					(thickness 0.15)
				)
				(justify left bottom)
				(hide yes)
			)
		)
		(property "Val" "100n"
			(at 179.07 186.6836 90)
			(effects
				(font
					(size 1.27 1.27)
					(thickness 0.15)
				)
				(justify right)
			)
		)
		(property "Voltage" "50V"
			(at 153.67 167.64 0)
			(effects
				(font
					(size 1.27 1.27)
				)
				(justify left bottom)
				(hide yes)
			)
		)
		(property "Dielectric" "X5R"
			(at 151.13 167.64 0)
			(effects
				(font
					(size 1.27 1.27)
				)
				(justify left bottom)
				(hide yes)
			)
		)
		(property "Public" "False"
			(at 148.59 167.64 0)
			(effects
				(font
					(size 1.27 1.27)
				)
				(justify left bottom)
				(hide yes)
			)
		)
		(pin "1"
		)
		(pin "2"
		)
		(instances
			(project "jetson-orin-baseboard-oculink-expansion"
				(path ""
					(reference "C8")
					(unit 1)
				)
			)
		)
	)
	(symbol
		(lib_id "antmicropower:GND")
		(at 276.86 176.53 0)
		(mirror y)
		(unit 1)
		(exclude_from_sim no)
		(in_bom yes)
		(on_board yes)
		(dnp no)
		(property "Reference" "#PWR067"
			(at 267.97 179.07 0)
			(effects
				(font
					(size 1.27 1.27)
					(thickness 0.15)
				)
				(justify left bottom)
				(hide yes)
			)
		)
		(property "Value" "GND"
			(at 276.86 180.34 0)
			(effects
				(font
					(size 1.27 1.27)
					(thickness 0.15)
				)
			)
		)
		(property "Footprint" ""
			(at 267.97 184.15 0)
			(effects
				(font
					(size 1.27 1.27)
					(thickness 0.15)
				)
				(justify left bottom)
				(hide yes)
			)
		)
		(property "Datasheet" ""
			(at 267.97 189.23 0)
			(effects
				(font
					(size 1.27 1.27)
					(thickness 0.15)
				)
				(justify left bottom)
				(hide yes)
			)
		)
		(property "Description" ""
			(at 276.86 176.53 0)
			(effects
				(font
					(size 1.27 1.27)
				)
				(hide yes)
			)
		)
		(property "Author" "Antmicro"
			(at 267.97 184.15 0)
			(effects
				(font
					(size 1.27 1.27)
					(thickness 0.15)
				)
				(justify left bottom)
				(hide yes)
			)
		)
		(property "License" "Apache-2.0"
			(at 267.97 186.69 0)
			(effects
				(font
					(size 1.27 1.27)
					(thickness 0.15)
				)
				(justify left bottom)
				(hide yes)
			)
		)
		(pin "1"
		)
		(instances
			(project "jetson-orin-baseboard-oculink-expansion"
				(path ""
					(reference "#PWR067")
					(unit 1)
				)
			)
		)
	)
	(symbol
		(lib_id "antmicroResistors0402:R_0R_0402")
		(at 323.85 68.58 0)
		(unit 1)
		(exclude_from_sim no)
		(in_bom yes)
		(on_board yes)
		(dnp no)
		(property "Reference" "R1"
			(at 322.58 67.564 0)
			(effects
				(font
					(size 1.27 1.27)
					(thickness 0.15)
				)
			)
		)
		(property "Value" "R_0R_0402"
			(at 344.17 81.28 0)
			(effects
				(font
					(size 1.27 1.27)
					(thickness 0.15)
				)
				(justify left bottom)
				(hide yes)
			)
		)
		(property "Footprint" "antmicro-footprints:R_0402_1005Metric"
			(at 344.17 83.82 0)
			(effects
				(font
					(size 1.27 1.27)
					(thickness 0.15)
				)
				(justify left bottom)
				(hide yes)
			)
		)
		(property "Datasheet" "https://industrial.panasonic.com/cdbs/www-data/pdf/RDA0000/AOA0000C301.pdf"
			(at 344.17 86.36 0)
			(effects
				(font
					(size 1.27 1.27)
					(thickness 0.15)
				)
				(justify left bottom)
				(hide yes)
			)
		)
		(property "Description" "SMD Chip Resistor, Jumper, 0 ohm, 100 mW, 0402 [1005 Metric], Thick Film, General Purpose"
			(at 323.85 68.58 0)
			(effects
				(font
					(size 1.27 1.27)
				)
				(hide yes)
			)
		)
		(property "MPN" "ERJ2GE0R00X"
			(at 344.17 88.9 0)
			(effects
				(font
					(size 1.27 1.27)
					(thickness 0.15)
				)
				(justify left bottom)
				(hide yes)
			)
		)
		(property "Manufacturer" "Panasonic"
			(at 344.17 91.44 0)
			(effects
				(font
					(size 1.27 1.27)
					(thickness 0.15)
				)
				(justify left bottom)
				(hide yes)
			)
		)
		(property "License" "Apache-2.0"
			(at 344.17 93.98 0)
			(effects
				(font
					(size 1.27 1.27)
					(thickness 0.15)
				)
				(justify left bottom)
				(hide yes)
			)
		)
		(property "Author" "Antmicro"
			(at 344.17 96.52 0)
			(effects
				(font
					(size 1.27 1.27)
					(thickness 0.15)
				)
				(justify left bottom)
				(hide yes)
			)
		)
		(property "Val" "0R"
			(at 330.2 67.564 0)
			(effects
				(font
					(size 1.27 1.27)
					(thickness 0.15)
				)
			)
		)
		(property "Tolerance" "~"
			(at 344.17 78.74 0)
			(effects
				(font
					(size 1.27 1.27)
				)
				(justify left bottom)
				(hide yes)
			)
		)
		(property "Current" "1A"
			(at 344.17 99.06 0)
			(effects
				(font
					(size 1.27 1.27)
					(thickness 0.15)
				)
				(justify left bottom)
				(hide yes)
			)
		)
		(pin "1"
		)
		(pin "2"
		)
		(instances
			(project "jetson-orin-baseboard-oculink-expansion"
				(path ""
					(reference "R1")
					(unit 1)
				)
			)
		)
	)
	(symbol
		(lib_id "antmicroResistors0402:R_1k_0402")
		(at 262.89 240.03 90)
		(mirror x)
		(unit 1)
		(exclude_from_sim no)
		(in_bom yes)
		(on_board yes)
		(dnp yes)
		(property "Reference" "R10"
			(at 262.89 236.22 0)
			(effects
				(font
					(size 1.27 1.27)
					(thickness 0.15)
				)
				(justify right)
			)
		)
		(property "Value" "R_1k_0402"
			(at 275.59 260.35 0)
			(effects
				(font
					(size 1.27 1.27)
					(thickness 0.15)
				)
				(justify left bottom)
				(hide yes)
			)
		)
		(property "Footprint" "antmicro-footprints:R_0402_1005Metric"
			(at 278.13 260.35 0)
			(effects
				(font
					(size 1.27 1.27)
					(thickness 0.15)
				)
				(justify left bottom)
				(hide yes)
			)
		)
		(property "Datasheet" "https://www.bourns.com/docs/product-datasheets/cr.pdf"
			(at 280.67 260.35 0)
			(effects
				(font
					(size 1.27 1.27)
					(thickness 0.15)
				)
				(justify left bottom)
				(hide yes)
			)
		)
		(property "Description" "SMD Chip Resistor, 1 kohm, ± 1%, 63 mW, 0402 [1005 Metric], Thick Film, General Purpose"
			(at 262.89 240.03 0)
			(effects
				(font
					(size 1.27 1.27)
				)
				(hide yes)
			)
		)
		(property "MPN" "CR0402-FX-1001GLF"
			(at 283.21 260.35 0)
			(effects
				(font
					(size 1.27 1.27)
					(thickness 0.15)
				)
				(justify left bottom)
				(hide yes)
			)
		)
		(property "Manufacturer" "Bourns"
			(at 285.75 260.35 0)
			(effects
				(font
					(size 1.27 1.27)
					(thickness 0.15)
				)
				(justify left bottom)
				(hide yes)
			)
		)
		(property "License" "Apache-2.0"
			(at 288.29 260.35 0)
			(effects
				(font
					(size 1.27 1.27)
					(thickness 0.15)
				)
				(justify left bottom)
				(hide yes)
			)
		)
		(property "Author" "Antmicro"
			(at 290.83 260.35 0)
			(effects
				(font
					(size 1.27 1.27)
					(thickness 0.15)
				)
				(justify left bottom)
				(hide yes)
			)
		)
		(property "Val" "1k"
			(at 261.62 240.03 0)
			(effects
				(font
					(size 1.27 1.27)
					(thickness 0.15)
				)
				(justify right)
			)
		)
		(property "Tolerance" "1%"
			(at 273.05 260.35 0)
			(effects
				(font
					(size 1.27 1.27)
				)
				(justify left bottom)
				(hide yes)
			)
		)
		(property "Public" "False"
			(at 293.37 260.35 0)
			(effects
				(font
					(size 1.27 1.27)
				)
				(justify left bottom)
				(hide yes)
			)
		)
		(pin "1"
		)
		(pin "2"
		)
		(instances
			(project "jetson-orin-baseboard-oculink-expansion"
				(path ""
					(reference "R10")
					(unit 1)
				)
			)
		)
	)
	(symbol
		(lib_id "antmicroTestPoints:TP_0.75mm_SMD")
		(at 198.12 104.14 0)
		(mirror y)
		(unit 1)
		(exclude_from_sim no)
		(in_bom no)
		(on_board yes)
		(dnp no)
		(property "Reference" "TP16"
			(at 191.77 104.14 0)
			(effects
				(font
					(size 1.27 1.27)
					(thickness 0.15)
				)
			)
		)
		(property "Value" "TP_0.75mm_SMD"
			(at 187.325 107.95 0)
			(effects
				(font
					(size 1.27 1.27)
					(thickness 0.15)
				)
				(justify left bottom)
				(hide yes)
			)
		)
		(property "Footprint" "antmicro-footprints:TP_SMD_0.75mm"
			(at 187.325 110.49 0)
			(effects
				(font
					(size 1.27 1.27)
					(thickness 0.15)
				)
				(justify left bottom)
				(hide yes)
			)
		)
		(property "Datasheet" ""
			(at 180.34 116.84 0)
			(effects
				(font
					(size 1.27 1.27)
					(thickness 0.15)
				)
				(justify left bottom)
				(hide yes)
			)
		)
		(property "Description" "SMT test point"
			(at 198.12 104.14 0)
			(effects
				(font
					(size 1.27 1.27)
				)
				(hide yes)
			)
		)
		(property "MPN" ""
			(at 187.325 115.57 0)
			(effects
				(font
					(size 1.27 1.27)
					(thickness 0.15)
				)
				(justify left bottom)
				(hide yes)
			)
		)
		(property "Manufacturer" ""
			(at 187.325 110.49 0)
			(effects
				(font
					(size 1.27 1.27)
					(thickness 0.15)
				)
				(justify left bottom)
				(hide yes)
			)
		)
		(property "Author" "Antmicro"
			(at 187.325 113.03 0)
			(effects
				(font
					(size 1.27 1.27)
					(thickness 0.15)
				)
				(justify left bottom)
				(hide yes)
			)
		)
		(property "License" "Apache-2.0"
			(at 187.325 115.57 0)
			(effects
				(font
					(size 1.27 1.27)
					(thickness 0.15)
				)
				(justify left bottom)
				(hide yes)
			)
		)
		(property "Public" "False"
			(at 187.96 118.11 0)
			(effects
				(font
					(size 1.27 1.27)
				)
				(justify left bottom)
				(hide yes)
			)
		)
		(pin "1"
		)
		(instances
			(project "jetson-orin-baseboard-oculink-expansion"
				(path ""
					(reference "TP16")
					(unit 1)
				)
			)
		)
	)
	(symbol
		(lib_id "antmicroMechanicalParts:oshw_logo")
		(at 25.4 270.51 0)
		(unit 1)
		(exclude_from_sim no)
		(in_bom no)
		(on_board yes)
		(dnp no)
		(fields_autoplaced yes)
		(property "Reference" "N3"
			(at 31.75 268.5262 0)
			(effects
				(font
					(size 1.27 1.27)
					(thickness 0.15)
				)
				(justify left)
			)
		)
		(property "Value" "oshw_logo"
			(at 31.75 271.0662 0)
			(effects
				(font
					(size 1.27 1.27)
					(thickness 0.15)
				)
				(justify left)
			)
		)
		(property "Footprint" "antmicro-footprints:oshw-logo"
			(at 40.64 280.67 0)
			(effects
				(font
					(size 1.27 1.27)
					(thickness 0.15)
				)
				(justify left bottom)
				(hide yes)
			)
		)
		(property "Datasheet" ""
			(at 40.64 283.21 0)
			(effects
				(font
					(size 1.27 1.27)
					(thickness 0.15)
				)
				(justify left bottom)
				(hide yes)
			)
		)
		(property "Description" "Mechanical part"
			(at 25.4 270.51 0)
			(effects
				(font
					(size 1.27 1.27)
				)
				(hide yes)
			)
		)
		(property "Author" "Antmicro"
			(at 40.64 285.75 0)
			(effects
				(font
					(size 1.27 1.27)
					(thickness 0.15)
				)
				(justify left bottom)
				(hide yes)
			)
		)
		(property "License" "Apache-2.0"
			(at 40.64 288.29 0)
			(effects
				(font
					(size 1.27 1.27)
					(thickness 0.15)
				)
				(justify left bottom)
				(hide yes)
			)
		)
		(property "MPN" ""
			(at 25.4 270.51 0)
			(effects
				(font
					(size 1.27 1.27)
				)
			)
		)
		(property "Manufacturer" ""
			(at 40.64 290.83 0)
			(effects
				(font
					(size 1.27 1.27)
					(thickness 0.15)
				)
				(justify left bottom)
				(hide yes)
			)
		)
		(instances
			(project "jetson-orin-baseboard-oculink-expansion"
				(path ""
					(reference "N3")
					(unit 1)
				)
			)
		)
	)
	(symbol
		(lib_id "antmicroPMICPowerDistributionSwitchesLoadDrivers:AP22615A_TSOT26")
		(at 260.35 121.92 0)
		(unit 1)
		(exclude_from_sim no)
		(in_bom yes)
		(on_board yes)
		(dnp no)
		(fields_autoplaced yes)
		(property "Reference" "U4"
			(at 267.97 113.03 0)
			(effects
				(font
					(size 1.27 1.27)
				)
			)
		)
		(property "Value" "~"
			(at 267.97 115.57 0)
			(effects
				(font
					(size 1.27 1.27)
				)
			)
		)
		(property "Footprint" "antmicro-footprints:TSOT23-6"
			(at 290.83 129.54 0)
			(effects
				(font
					(size 1.27 1.27)
					(thickness 0.15)
				)
				(justify left bottom)
				(hide yes)
			)
		)
		(property "Datasheet" "https://www.mouser.com/datasheet/2/115/DIOD_S_A0008958405_1-2543193.pdf"
			(at 290.83 132.08 0)
			(effects
				(font
					(size 1.27 1.27)
					(thickness 0.15)
				)
				(justify left bottom)
				(hide yes)
			)
		)
		(property "Description" "Power Load Distribution Switch, High Side, Active High, 1 Output, 5.5 V, 3.6 A, 0.04 ohm, TSOT-26-6"
			(at 260.35 121.92 0)
			(effects
				(font
					(size 1.27 1.27)
				)
				(hide yes)
			)
		)
		(property "MPN" "AP22615AWU-7"
			(at 267.97 116.84 0)
			(effects
				(font
					(size 1.27 1.27)
					(thickness 0.15)
				)
			)
		)
		(property "Manufacturer" "Diodes Incorporated"
			(at 290.83 137.16 0)
			(effects
				(font
					(size 1.27 1.27)
					(thickness 0.15)
				)
				(justify left bottom)
				(hide yes)
			)
		)
		(property "Author" "Antmicro"
			(at 290.83 139.7 0)
			(effects
				(font
					(size 1.27 1.27)
					(thickness 0.15)
				)
				(justify left bottom)
				(hide yes)
			)
		)
		(property "License" "Apache-2.0"
			(at 290.83 142.24 0)
			(effects
				(font
					(size 1.27 1.27)
					(thickness 0.15)
				)
				(justify left bottom)
				(hide yes)
			)
		)
		(pin "5"
		)
		(pin "3"
		)
		(pin "6"
		)
		(pin "1"
		)
		(pin "4"
		)
		(pin "2"
		)
		(instances
			(project ""
				(path ""
					(reference "U4")
					(unit 1)
				)
			)
		)
	)
	(symbol
		(lib_id "antmicropower:GND")
		(at 173.99 105.41 0)
		(mirror y)
		(unit 1)
		(exclude_from_sim no)
		(in_bom yes)
		(on_board yes)
		(dnp no)
		(property "Reference" "#PWR048"
			(at 165.1 107.95 0)
			(effects
				(font
					(size 1.27 1.27)
					(thickness 0.15)
				)
				(justify left bottom)
				(hide yes)
			)
		)
		(property "Value" "GND"
			(at 170.18 106.68 0)
			(effects
				(font
					(size 1.27 1.27)
					(thickness 0.15)
				)
			)
		)
		(property "Footprint" ""
			(at 165.1 113.03 0)
			(effects
				(font
					(size 1.27 1.27)
					(thickness 0.15)
				)
				(justify left bottom)
				(hide yes)
			)
		)
		(property "Datasheet" ""
			(at 165.1 118.11 0)
			(effects
				(font
					(size 1.27 1.27)
					(thickness 0.15)
				)
				(justify left bottom)
				(hide yes)
			)
		)
		(property "Description" ""
			(at 173.99 105.41 0)
			(effects
				(font
					(size 1.27 1.27)
				)
				(hide yes)
			)
		)
		(property "Author" "Antmicro"
			(at 165.1 113.03 0)
			(effects
				(font
					(size 1.27 1.27)
					(thickness 0.15)
				)
				(justify left bottom)
				(hide yes)
			)
		)
		(property "License" "Apache-2.0"
			(at 165.1 115.57 0)
			(effects
				(font
					(size 1.27 1.27)
					(thickness 0.15)
				)
				(justify left bottom)
				(hide yes)
			)
		)
		(pin "1"
		)
		(instances
			(project "jetson-orin-baseboard-oculink-expansion"
				(path ""
					(reference "#PWR048")
					(unit 1)
				)
			)
		)
	)
	(symbol
		(lib_id "antmicroResistors0402:R_1k_0402")
		(at 160.02 101.6 270)
		(unit 1)
		(exclude_from_sim no)
		(in_bom yes)
		(on_board yes)
		(dnp no)
		(property "Reference" "R27"
			(at 160.02 97.79 0)
			(effects
				(font
					(size 1.27 1.27)
					(thickness 0.15)
				)
				(justify right)
			)
		)
		(property "Value" "R_1k_0402"
			(at 147.32 121.92 0)
			(effects
				(font
					(size 1.27 1.27)
					(thickness 0.15)
				)
				(justify left bottom)
				(hide yes)
			)
		)
		(property "Footprint" "antmicro-footprints:R_0402_1005Metric"
			(at 144.78 121.92 0)
			(effects
				(font
					(size 1.27 1.27)
					(thickness 0.15)
				)
				(justify left bottom)
				(hide yes)
			)
		)
		(property "Datasheet" "https://www.bourns.com/docs/product-datasheets/cr.pdf"
			(at 142.24 121.92 0)
			(effects
				(font
					(size 1.27 1.27)
					(thickness 0.15)
				)
				(justify left bottom)
				(hide yes)
			)
		)
		(property "Description" "SMD Chip Resistor, 1 kohm, ± 1%, 63 mW, 0402 [1005 Metric], Thick Film, General Purpose"
			(at 160.02 101.6 0)
			(effects
				(font
					(size 1.27 1.27)
				)
				(hide yes)
			)
		)
		(property "MPN" "CR0402-FX-1001GLF"
			(at 139.7 121.92 0)
			(effects
				(font
					(size 1.27 1.27)
					(thickness 0.15)
				)
				(justify left bottom)
				(hide yes)
			)
		)
		(property "Manufacturer" "Bourns"
			(at 137.16 121.92 0)
			(effects
				(font
					(size 1.27 1.27)
					(thickness 0.15)
				)
				(justify left bottom)
				(hide yes)
			)
		)
		(property "License" "Apache-2.0"
			(at 134.62 121.92 0)
			(effects
				(font
					(size 1.27 1.27)
					(thickness 0.15)
				)
				(justify left bottom)
				(hide yes)
			)
		)
		(property "Author" "Antmicro"
			(at 132.08 121.92 0)
			(effects
				(font
					(size 1.27 1.27)
					(thickness 0.15)
				)
				(justify left bottom)
				(hide yes)
			)
		)
		(property "Val" "1k"
			(at 161.29 101.6 0)
			(effects
				(font
					(size 1.27 1.27)
					(thickness 0.15)
				)
				(justify right)
			)
		)
		(property "Tolerance" "1%"
			(at 149.86 121.92 0)
			(effects
				(font
					(size 1.27 1.27)
				)
				(justify left bottom)
				(hide yes)
			)
		)
		(property "Public" "False"
			(at 129.54 121.92 0)
			(effects
				(font
					(size 1.27 1.27)
				)
				(justify left bottom)
				(hide yes)
			)
		)
		(pin "1"
		)
		(pin "2"
		)
		(instances
			(project "jetson-orin-baseboard-oculink-expansion"
				(path ""
					(reference "R27")
					(unit 1)
				)
			)
		)
	)
	(symbol
		(lib_id "antmicropower:GND")
		(at 156.21 49.53 0)
		(unit 1)
		(exclude_from_sim no)
		(in_bom yes)
		(on_board yes)
		(dnp no)
		(property "Reference" "#PWR038"
			(at 165.1 52.07 0)
			(effects
				(font
					(size 1.27 1.27)
					(thickness 0.15)
				)
				(justify left bottom)
				(hide yes)
			)
		)
		(property "Value" "GND"
			(at 156.21 53.34 0)
			(effects
				(font
					(size 1.27 1.27)
					(thickness 0.15)
				)
			)
		)
		(property "Footprint" ""
			(at 165.1 57.15 0)
			(effects
				(font
					(size 1.27 1.27)
					(thickness 0.15)
				)
				(justify left bottom)
				(hide yes)
			)
		)
		(property "Datasheet" ""
			(at 165.1 62.23 0)
			(effects
				(font
					(size 1.27 1.27)
					(thickness 0.15)
				)
				(justify left bottom)
				(hide yes)
			)
		)
		(property "Description" ""
			(at 156.21 49.53 0)
			(effects
				(font
					(size 1.27 1.27)
				)
				(hide yes)
			)
		)
		(property "Author" "Antmicro"
			(at 165.1 57.15 0)
			(effects
				(font
					(size 1.27 1.27)
					(thickness 0.15)
				)
				(justify left bottom)
				(hide yes)
			)
		)
		(property "License" "Apache-2.0"
			(at 165.1 59.69 0)
			(effects
				(font
					(size 1.27 1.27)
					(thickness 0.15)
				)
				(justify left bottom)
				(hide yes)
			)
		)
		(pin "1"
		)
		(instances
			(project "jetson-orin-baseboard-oculink-expansion"
				(path ""
					(reference "#PWR038")
					(unit 1)
				)
			)
		)
	)
	(symbol
		(lib_id "antmicropower:GND")
		(at 345.44 243.84 0)
		(mirror y)
		(unit 1)
		(exclude_from_sim no)
		(in_bom yes)
		(on_board yes)
		(dnp no)
		(fields_autoplaced yes)
		(property "Reference" "#PWR022"
			(at 345.44 250.19 0)
			(effects
				(font
					(size 1.27 1.27)
				)
				(justify left bottom)
				(hide yes)
			)
		)
		(property "Value" "GND"
			(at 345.44 247.65 0)
			(effects
				(font
					(size 1.27 1.27)
					(thickness 0.15)
				)
			)
		)
		(property "Footprint" ""
			(at 336.55 251.46 0)
			(effects
				(font
					(size 1.27 1.27)
					(thickness 0.15)
				)
				(justify left bottom)
				(hide yes)
			)
		)
		(property "Datasheet" ""
			(at 336.55 256.54 0)
			(effects
				(font
					(size 1.27 1.27)
					(thickness 0.15)
				)
				(justify left bottom)
				(hide yes)
			)
		)
		(property "Description" ""
			(at 345.44 243.84 0)
			(effects
				(font
					(size 1.27 1.27)
				)
				(hide yes)
			)
		)
		(property "Author" "Antmicro"
			(at 336.55 251.46 0)
			(effects
				(font
					(size 1.27 1.27)
					(thickness 0.15)
				)
				(justify left bottom)
				(hide yes)
			)
		)
		(property "License" "Apache-2.0"
			(at 336.55 254 0)
			(effects
				(font
					(size 1.27 1.27)
					(thickness 0.15)
				)
				(justify left bottom)
				(hide yes)
			)
		)
		(pin "1"
		)
		(instances
			(project "jetson-orin-baseboard-oculink-expansion"
				(path ""
					(reference "#PWR022")
					(unit 1)
				)
			)
		)
	)
	(symbol
		(lib_id "antmicropower:+3V3")
		(at 147.32 96.52 0)
		(unit 1)
		(exclude_from_sim no)
		(in_bom yes)
		(on_board yes)
		(dnp no)
		(property "Reference" "#PWR042"
			(at 162.56 96.52 0)
			(effects
				(font
					(size 1.27 1.27)
					(thickness 0.15)
				)
				(justify left bottom)
				(hide yes)
			)
		)
		(property "Value" "+3V3"
			(at 146.05 92.71 0)
			(effects
				(font
					(size 1.27 1.27)
					(thickness 0.15)
				)
			)
		)
		(property "Footprint" ""
			(at 162.56 104.14 0)
			(effects
				(font
					(size 1.27 1.27)
					(thickness 0.15)
				)
				(justify left bottom)
				(hide yes)
			)
		)
		(property "Datasheet" ""
			(at 162.56 106.68 0)
			(effects
				(font
					(size 1.27 1.27)
					(thickness 0.15)
				)
				(justify left bottom)
				(hide yes)
			)
		)
		(property "Description" ""
			(at 147.32 96.52 0)
			(effects
				(font
					(size 1.27 1.27)
				)
				(hide yes)
			)
		)
		(property "Author" "Antmicro"
			(at 162.56 99.06 0)
			(effects
				(font
					(size 1.27 1.27)
					(thickness 0.15)
				)
				(justify left bottom)
				(hide yes)
			)
		)
		(property "License" "Apache-2.0"
			(at 162.56 101.6 0)
			(effects
				(font
					(size 1.27 1.27)
					(thickness 0.15)
				)
				(justify left bottom)
				(hide yes)
			)
		)
		(pin "1"
		)
		(instances
			(project "jetson-orin-baseboard-oculink-expansion"
				(path ""
					(reference "#PWR042")
					(unit 1)
				)
			)
		)
	)
	(symbol
		(lib_id "antmicroCapacitors0402:C_100n_0402")
		(at 289.56 175.26 90)
		(unit 1)
		(exclude_from_sim no)
		(in_bom yes)
		(on_board yes)
		(dnp no)
		(property "Reference" "C34"
			(at 291.338 171.704 90)
			(effects
				(font
					(size 1.27 1.27)
					(thickness 0.15)
				)
				(justify right)
			)
		)
		(property "Value" "C_100n_0402"
			(at 299.72 154.94 0)
			(effects
				(font
					(size 1.27 1.27)
					(thickness 0.15)
				)
				(justify left bottom)
				(hide yes)
			)
		)
		(property "Footprint" "antmicro-footprints:C_0402_1005Metric"
			(at 302.26 154.94 0)
			(effects
				(font
					(size 1.27 1.27)
					(thickness 0.15)
				)
				(justify left bottom)
				(hide yes)
			)
		)
		(property "Datasheet" "https://www.murata.com/products/productdetail?partno=GRM155R61H104KE14%23"
			(at 304.8 154.94 0)
			(effects
				(font
					(size 1.27 1.27)
					(thickness 0.15)
				)
				(justify left bottom)
				(hide yes)
			)
		)
		(property "Description" "SMD Multilayer Ceramic Capacitor, 0.1 µF, 50 V, 0402 [1005 Metric], ± 10%, X5R, GRM Series"
			(at 289.56 175.26 0)
			(effects
				(font
					(size 1.27 1.27)
				)
				(hide yes)
			)
		)
		(property "MPN" "GRM155R61H104KE14D"
			(at 307.34 154.94 0)
			(effects
				(font
					(size 1.27 1.27)
					(thickness 0.15)
				)
				(justify left bottom)
				(hide yes)
			)
		)
		(property "Manufacturer" "Murata"
			(at 309.88 154.94 0)
			(effects
				(font
					(size 1.27 1.27)
					(thickness 0.15)
				)
				(justify left bottom)
				(hide yes)
			)
		)
		(property "License" "Apache-2.0"
			(at 312.42 154.94 0)
			(effects
				(font
					(size 1.27 1.27)
					(thickness 0.15)
				)
				(justify left bottom)
				(hide yes)
			)
		)
		(property "Author" "Antmicro"
			(at 314.96 154.94 0)
			(effects
				(font
					(size 1.27 1.27)
					(thickness 0.15)
				)
				(justify left bottom)
				(hide yes)
			)
		)
		(property "Val" "100n"
			(at 291.338 174.244 90)
			(effects
				(font
					(size 1.27 1.27)
					(thickness 0.15)
				)
				(justify right)
			)
		)
		(property "Voltage" "50V"
			(at 317.5 154.94 0)
			(effects
				(font
					(size 1.27 1.27)
				)
				(justify left bottom)
				(hide yes)
			)
		)
		(property "Dielectric" "X5R"
			(at 320.04 154.94 0)
			(effects
				(font
					(size 1.27 1.27)
				)
				(justify left bottom)
				(hide yes)
			)
		)
		(pin "1"
		)
		(pin "2"
		)
		(instances
			(project "jetson-orin-baseboard-oculink-expansion"
				(path ""
					(reference "C34")
					(unit 1)
				)
			)
		)
	)
	(symbol
		(lib_id "antmicroResistors0402:R_10k_0402")
		(at 245.11 217.17 90)
		(unit 1)
		(exclude_from_sim no)
		(in_bom yes)
		(on_board yes)
		(dnp no)
		(property "Reference" "R41"
			(at 247.65 212.598 0)
			(effects
				(font
					(size 1.27 1.27)
					(thickness 0.15)
				)
				(justify right)
			)
		)
		(property "Value" "R_10k_0402"
			(at 257.81 196.85 0)
			(effects
				(font
					(size 1.27 1.27)
					(thickness 0.15)
				)
				(justify left bottom)
				(hide yes)
			)
		)
		(property "Footprint" "antmicro-footprints:R_0402_1005Metric"
			(at 260.35 196.85 0)
			(effects
				(font
					(size 1.27 1.27)
					(thickness 0.15)
				)
				(justify left bottom)
				(hide yes)
			)
		)
		(property "Datasheet" "https://www.bourns.com/docs/product-datasheets/cr.pdf"
			(at 262.89 196.85 0)
			(effects
				(font
					(size 1.27 1.27)
					(thickness 0.15)
				)
				(justify left bottom)
				(hide yes)
			)
		)
		(property "Description" "SMD Chip Resistor, 10 kohm, ± 1%, 62.5 mW, 0402 [1005 Metric], Thick Film, General Purpose"
			(at 245.11 217.17 0)
			(effects
				(font
					(size 1.27 1.27)
				)
				(hide yes)
			)
		)
		(property "MPN" "CR0402-FX-1002GLF"
			(at 265.43 196.85 0)
			(effects
				(font
					(size 1.27 1.27)
					(thickness 0.15)
				)
				(justify left bottom)
				(hide yes)
			)
		)
		(property "Manufacturer" "Bourns"
			(at 267.97 196.85 0)
			(effects
				(font
					(size 1.27 1.27)
					(thickness 0.15)
				)
				(justify left bottom)
				(hide yes)
			)
		)
		(property "License" "Apache-2.0"
			(at 270.51 196.85 0)
			(effects
				(font
					(size 1.27 1.27)
					(thickness 0.15)
				)
				(justify left bottom)
				(hide yes)
			)
		)
		(property "Author" "Antmicro"
			(at 273.05 196.85 0)
			(effects
				(font
					(size 1.27 1.27)
					(thickness 0.15)
				)
				(justify left bottom)
				(hide yes)
			)
		)
		(property "Val" "10k"
			(at 249.428 212.852 0)
			(effects
				(font
					(size 1.27 1.27)
					(thickness 0.15)
				)
				(justify right)
			)
		)
		(property "Tolerance" "1%"
			(at 255.27 196.85 0)
			(effects
				(font
					(size 1.27 1.27)
				)
				(justify left bottom)
				(hide yes)
			)
		)
		(pin "2"
		)
		(pin "1"
		)
		(instances
			(project "jetson-orin-baseboard-oculink-expansion"
				(path ""
					(reference "R41")
					(unit 1)
				)
			)
		)
	)
	(symbol
		(lib_id "antmicroCapacitors0402:C_100n_0402")
		(at 163.83 172.72 270)
		(mirror x)
		(unit 1)
		(exclude_from_sim no)
		(in_bom yes)
		(on_board yes)
		(dnp no)
		(fields_autoplaced yes)
		(property "Reference" "C11"
			(at 161.29 168.9036 90)
			(effects
				(font
					(size 1.27 1.27)
					(thickness 0.15)
				)
				(justify right)
			)
		)
		(property "Value" "C_100n_0402"
			(at 153.67 152.4 0)
			(effects
				(font
					(size 1.27 1.27)
					(thickness 0.15)
				)
				(justify left bottom)
				(hide yes)
			)
		)
		(property "Footprint" "antmicro-footprints:C_0402_1005Metric"
			(at 151.13 152.4 0)
			(effects
				(font
					(size 1.27 1.27)
					(thickness 0.15)
				)
				(justify left bottom)
				(hide yes)
			)
		)
		(property "Datasheet" "https://www.murata.com/products/productdetail?partno=GRM155R61H104KE14%23"
			(at 148.59 152.4 0)
			(effects
				(font
					(size 1.27 1.27)
					(thickness 0.15)
				)
				(justify left bottom)
				(hide yes)
			)
		)
		(property "Description" "SMD Multilayer Ceramic Capacitor, 0.1 µF, 50 V, 0402 [1005 Metric], ± 10%, X5R, GRM Series"
			(at 163.83 172.72 0)
			(effects
				(font
					(size 1.27 1.27)
				)
				(hide yes)
			)
		)
		(property "MPN" "GRM155R61H104KE14D"
			(at 146.05 152.4 0)
			(effects
				(font
					(size 1.27 1.27)
					(thickness 0.15)
				)
				(justify left bottom)
				(hide yes)
			)
		)
		(property "Manufacturer" "Murata"
			(at 143.51 152.4 0)
			(effects
				(font
					(size 1.27 1.27)
					(thickness 0.15)
				)
				(justify left bottom)
				(hide yes)
			)
		)
		(property "License" "Apache-2.0"
			(at 140.97 152.4 0)
			(effects
				(font
					(size 1.27 1.27)
					(thickness 0.15)
				)
				(justify left bottom)
				(hide yes)
			)
		)
		(property "Author" "Antmicro"
			(at 138.43 152.4 0)
			(effects
				(font
					(size 1.27 1.27)
					(thickness 0.15)
				)
				(justify left bottom)
				(hide yes)
			)
		)
		(property "Val" "100n"
			(at 161.29 171.4436 90)
			(effects
				(font
					(size 1.27 1.27)
					(thickness 0.15)
				)
				(justify right)
			)
		)
		(property "Voltage" "50V"
			(at 135.89 152.4 0)
			(effects
				(font
					(size 1.27 1.27)
				)
				(justify left bottom)
				(hide yes)
			)
		)
		(property "Dielectric" "X5R"
			(at 133.35 152.4 0)
			(effects
				(font
					(size 1.27 1.27)
				)
				(justify left bottom)
				(hide yes)
			)
		)
		(property "Public" "False"
			(at 130.81 152.4 0)
			(effects
				(font
					(size 1.27 1.27)
				)
				(justify left bottom)
				(hide yes)
			)
		)
		(pin "1"
		)
		(pin "2"
		)
		(instances
			(project "jetson-orin-baseboard-oculink-expansion"
				(path ""
					(reference "C11")
					(unit 1)
				)
			)
		)
	)
	(symbol
		(lib_id "antmicropower:GND")
		(at 147.32 49.53 0)
		(unit 1)
		(exclude_from_sim no)
		(in_bom yes)
		(on_board yes)
		(dnp no)
		(property "Reference" "#PWR034"
			(at 156.21 52.07 0)
			(effects
				(font
					(size 1.27 1.27)
					(thickness 0.15)
				)
				(justify left bottom)
				(hide yes)
			)
		)
		(property "Value" "GND"
			(at 147.32 53.34 0)
			(effects
				(font
					(size 1.27 1.27)
					(thickness 0.15)
				)
			)
		)
		(property "Footprint" ""
			(at 156.21 57.15 0)
			(effects
				(font
					(size 1.27 1.27)
					(thickness 0.15)
				)
				(justify left bottom)
				(hide yes)
			)
		)
		(property "Datasheet" ""
			(at 156.21 62.23 0)
			(effects
				(font
					(size 1.27 1.27)
					(thickness 0.15)
				)
				(justify left bottom)
				(hide yes)
			)
		)
		(property "Description" ""
			(at 147.32 49.53 0)
			(effects
				(font
					(size 1.27 1.27)
				)
				(hide yes)
			)
		)
		(property "Author" "Antmicro"
			(at 156.21 57.15 0)
			(effects
				(font
					(size 1.27 1.27)
					(thickness 0.15)
				)
				(justify left bottom)
				(hide yes)
			)
		)
		(property "License" "Apache-2.0"
			(at 156.21 59.69 0)
			(effects
				(font
					(size 1.27 1.27)
					(thickness 0.15)
				)
				(justify left bottom)
				(hide yes)
			)
		)
		(pin "1"
		)
		(instances
			(project "jetson-orin-baseboard-oculink-expansion"
				(path ""
					(reference "#PWR034")
					(unit 1)
				)
			)
		)
	)
	(symbol
		(lib_id "antmicropower:+3.3V")
		(at 364.49 187.96 0)
		(unit 1)
		(exclude_from_sim no)
		(in_bom yes)
		(on_board yes)
		(dnp no)
		(fields_autoplaced yes)
		(property "Reference" "#PWR015"
			(at 364.49 191.77 0)
			(effects
				(font
					(size 1.27 1.27)
				)
				(hide yes)
			)
		)
		(property "Value" "+3V3"
			(at 364.49 182.88 0)
			(effects
				(font
					(size 1.27 1.27)
				)
			)
		)
		(property "Footprint" ""
			(at 364.49 187.96 0)
			(effects
				(font
					(size 1.27 1.27)
				)
				(hide yes)
			)
		)
		(property "Datasheet" ""
			(at 364.49 187.96 0)
			(effects
				(font
					(size 1.27 1.27)
				)
				(hide yes)
			)
		)
		(property "Description" ""
			(at 364.49 187.96 0)
			(effects
				(font
					(size 1.27 1.27)
				)
				(hide yes)
			)
		)
		(pin "1"
		)
		(instances
			(project "jetson-orin-baseboard-oculink-expansion"
				(path ""
					(reference "#PWR015")
					(unit 1)
				)
			)
		)
	)
	(symbol
		(lib_id "antmicropower:GND")
		(at 289.56 176.53 0)
		(mirror y)
		(unit 1)
		(exclude_from_sim no)
		(in_bom yes)
		(on_board yes)
		(dnp no)
		(property "Reference" "#PWR069"
			(at 280.67 179.07 0)
			(effects
				(font
					(size 1.27 1.27)
					(thickness 0.15)
				)
				(justify left bottom)
				(hide yes)
			)
		)
		(property "Value" "GND"
			(at 289.56 180.34 0)
			(effects
				(font
					(size 1.27 1.27)
					(thickness 0.15)
				)
			)
		)
		(property "Footprint" ""
			(at 280.67 184.15 0)
			(effects
				(font
					(size 1.27 1.27)
					(thickness 0.15)
				)
				(justify left bottom)
				(hide yes)
			)
		)
		(property "Datasheet" ""
			(at 280.67 189.23 0)
			(effects
				(font
					(size 1.27 1.27)
					(thickness 0.15)
				)
				(justify left bottom)
				(hide yes)
			)
		)
		(property "Description" ""
			(at 289.56 176.53 0)
			(effects
				(font
					(size 1.27 1.27)
				)
				(hide yes)
			)
		)
		(property "Author" "Antmicro"
			(at 280.67 184.15 0)
			(effects
				(font
					(size 1.27 1.27)
					(thickness 0.15)
				)
				(justify left bottom)
				(hide yes)
			)
		)
		(property "License" "Apache-2.0"
			(at 280.67 186.69 0)
			(effects
				(font
					(size 1.27 1.27)
					(thickness 0.15)
				)
				(justify left bottom)
				(hide yes)
			)
		)
		(pin "1"
		)
		(instances
			(project "jetson-orin-baseboard-oculink-expansion"
				(path ""
					(reference "#PWR069")
					(unit 1)
				)
			)
		)
	)
	(symbol
		(lib_id "antmicropower:+3V3")
		(at 273.05 234.95 0)
		(mirror y)
		(unit 1)
		(exclude_from_sim no)
		(in_bom yes)
		(on_board yes)
		(dnp no)
		(property "Reference" "#PWR028"
			(at 257.81 234.95 0)
			(effects
				(font
					(size 1.27 1.27)
					(thickness 0.15)
				)
				(justify left bottom)
				(hide yes)
			)
		)
		(property "Value" "+3V3"
			(at 274.32 231.14 0)
			(effects
				(font
					(size 1.27 1.27)
					(thickness 0.15)
				)
			)
		)
		(property "Footprint" ""
			(at 257.81 242.57 0)
			(effects
				(font
					(size 1.27 1.27)
					(thickness 0.15)
				)
				(justify left bottom)
				(hide yes)
			)
		)
		(property "Datasheet" ""
			(at 257.81 245.11 0)
			(effects
				(font
					(size 1.27 1.27)
					(thickness 0.15)
				)
				(justify left bottom)
				(hide yes)
			)
		)
		(property "Description" ""
			(at 273.05 234.95 0)
			(effects
				(font
					(size 1.27 1.27)
				)
				(hide yes)
			)
		)
		(property "Author" "Antmicro"
			(at 257.81 237.49 0)
			(effects
				(font
					(size 1.27 1.27)
					(thickness 0.15)
				)
				(justify left bottom)
				(hide yes)
			)
		)
		(property "License" "Apache-2.0"
			(at 257.81 240.03 0)
			(effects
				(font
					(size 1.27 1.27)
					(thickness 0.15)
				)
				(justify left bottom)
				(hide yes)
			)
		)
		(pin "1"
		)
		(instances
			(project "jetson-orin-baseboard-oculink-expansion"
				(path ""
					(reference "#PWR028")
					(unit 1)
				)
			)
		)
	)
	(symbol
		(lib_id "antmicroResistors0402:R_0R_0402")
		(at 323.85 71.12 0)
		(unit 1)
		(exclude_from_sim no)
		(in_bom yes)
		(on_board yes)
		(dnp no)
		(property "Reference" "R2"
			(at 322.58 70.104 0)
			(effects
				(font
					(size 1.27 1.27)
					(thickness 0.15)
				)
			)
		)
		(property "Value" "R_0R_0402"
			(at 344.17 83.82 0)
			(effects
				(font
					(size 1.27 1.27)
					(thickness 0.15)
				)
				(justify left bottom)
				(hide yes)
			)
		)
		(property "Footprint" "antmicro-footprints:R_0402_1005Metric"
			(at 344.17 86.36 0)
			(effects
				(font
					(size 1.27 1.27)
					(thickness 0.15)
				)
				(justify left bottom)
				(hide yes)
			)
		)
		(property "Datasheet" "https://industrial.panasonic.com/cdbs/www-data/pdf/RDA0000/AOA0000C301.pdf"
			(at 344.17 88.9 0)
			(effects
				(font
					(size 1.27 1.27)
					(thickness 0.15)
				)
				(justify left bottom)
				(hide yes)
			)
		)
		(property "Description" "SMD Chip Resistor, Jumper, 0 ohm, 100 mW, 0402 [1005 Metric], Thick Film, General Purpose"
			(at 323.85 71.12 0)
			(effects
				(font
					(size 1.27 1.27)
				)
				(hide yes)
			)
		)
		(property "MPN" "ERJ2GE0R00X"
			(at 344.17 91.44 0)
			(effects
				(font
					(size 1.27 1.27)
					(thickness 0.15)
				)
				(justify left bottom)
				(hide yes)
			)
		)
		(property "Manufacturer" "Panasonic"
			(at 344.17 93.98 0)
			(effects
				(font
					(size 1.27 1.27)
					(thickness 0.15)
				)
				(justify left bottom)
				(hide yes)
			)
		)
		(property "License" "Apache-2.0"
			(at 344.17 96.52 0)
			(effects
				(font
					(size 1.27 1.27)
					(thickness 0.15)
				)
				(justify left bottom)
				(hide yes)
			)
		)
		(property "Author" "Antmicro"
			(at 344.17 99.06 0)
			(effects
				(font
					(size 1.27 1.27)
					(thickness 0.15)
				)
				(justify left bottom)
				(hide yes)
			)
		)
		(property "Val" "0R"
			(at 330.2 70.104 0)
			(effects
				(font
					(size 1.27 1.27)
					(thickness 0.15)
				)
			)
		)
		(property "Tolerance" "~"
			(at 344.17 81.28 0)
			(effects
				(font
					(size 1.27 1.27)
				)
				(justify left bottom)
				(hide yes)
			)
		)
		(property "Current" "1A"
			(at 344.17 101.6 0)
			(effects
				(font
					(size 1.27 1.27)
					(thickness 0.15)
				)
				(justify left bottom)
				(hide yes)
			)
		)
		(pin "1"
		)
		(pin "2"
		)
		(instances
			(project ""
				(path ""
					(reference "R2")
					(unit 1)
				)
			)
		)
	)
	(symbol
		(lib_id "antmicropower:GND")
		(at 298.45 132.08 0)
		(mirror y)
		(unit 1)
		(exclude_from_sim no)
		(in_bom yes)
		(on_board yes)
		(dnp no)
		(property "Reference" "#PWR066"
			(at 289.56 134.62 0)
			(effects
				(font
					(size 1.27 1.27)
					(thickness 0.15)
				)
				(justify left bottom)
				(hide yes)
			)
		)
		(property "Value" "GND"
			(at 298.45 135.89 0)
			(effects
				(font
					(size 1.27 1.27)
					(thickness 0.15)
				)
			)
		)
		(property "Footprint" ""
			(at 289.56 139.7 0)
			(effects
				(font
					(size 1.27 1.27)
					(thickness 0.15)
				)
				(justify left bottom)
				(hide yes)
			)
		)
		(property "Datasheet" ""
			(at 289.56 144.78 0)
			(effects
				(font
					(size 1.27 1.27)
					(thickness 0.15)
				)
				(justify left bottom)
				(hide yes)
			)
		)
		(property "Description" ""
			(at 298.45 132.08 0)
			(effects
				(font
					(size 1.27 1.27)
				)
				(hide yes)
			)
		)
		(property "Author" "Antmicro"
			(at 289.56 139.7 0)
			(effects
				(font
					(size 1.27 1.27)
					(thickness 0.15)
				)
				(justify left bottom)
				(hide yes)
			)
		)
		(property "License" "Apache-2.0"
			(at 289.56 142.24 0)
			(effects
				(font
					(size 1.27 1.27)
					(thickness 0.15)
				)
				(justify left bottom)
				(hide yes)
			)
		)
		(pin "1"
		)
		(instances
			(project "jetson-orin-baseboard-oculink-expansion"
				(path ""
					(reference "#PWR066")
					(unit 1)
				)
			)
		)
	)
	(symbol
		(lib_id "antmicroResistors0402:R_0R_0402")
		(at 256.54 220.98 0)
		(mirror y)
		(unit 1)
		(exclude_from_sim no)
		(in_bom yes)
		(on_board yes)
		(dnp yes)
		(property "Reference" "R37"
			(at 251.968 225.298 0)
			(effects
				(font
					(size 1.27 1.27)
					(thickness 0.15)
				)
				(justify right)
			)
		)
		(property "Value" "R_0R_0402"
			(at 236.22 233.68 0)
			(effects
				(font
					(size 1.27 1.27)
					(thickness 0.15)
				)
				(justify left bottom)
				(hide yes)
			)
		)
		(property "Footprint" "antmicro-footprints:R_0402_1005Metric"
			(at 236.22 236.22 0)
			(effects
				(font
					(size 1.27 1.27)
					(thickness 0.15)
				)
				(justify left bottom)
				(hide yes)
			)
		)
		(property "Datasheet" "https://industrial.panasonic.com/cdbs/www-data/pdf/RDA0000/AOA0000C301.pdf"
			(at 236.22 238.76 0)
			(effects
				(font
					(size 1.27 1.27)
					(thickness 0.15)
				)
				(justify left bottom)
				(hide yes)
			)
		)
		(property "Description" "SMD Chip Resistor, Jumper, 0 ohm, 100 mW, 0402 [1005 Metric], Thick Film, General Purpose"
			(at 256.54 220.98 0)
			(effects
				(font
					(size 1.27 1.27)
				)
				(hide yes)
			)
		)
		(property "MPN" "ERJ2GE0R00X"
			(at 236.22 241.3 0)
			(effects
				(font
					(size 1.27 1.27)
					(thickness 0.15)
				)
				(justify left bottom)
				(hide yes)
			)
		)
		(property "Manufacturer" "Panasonic"
			(at 236.22 243.84 0)
			(effects
				(font
					(size 1.27 1.27)
					(thickness 0.15)
				)
				(justify left bottom)
				(hide yes)
			)
		)
		(property "License" "Apache-2.0"
			(at 236.22 246.38 0)
			(effects
				(font
					(size 1.27 1.27)
					(thickness 0.15)
				)
				(justify left bottom)
				(hide yes)
			)
		)
		(property "Author" "Antmicro"
			(at 236.22 248.92 0)
			(effects
				(font
					(size 1.27 1.27)
					(thickness 0.15)
				)
				(justify left bottom)
				(hide yes)
			)
		)
		(property "Val" "0R"
			(at 253.238 223.52 0)
			(effects
				(font
					(size 1.27 1.27)
					(thickness 0.15)
				)
				(justify right)
			)
		)
		(property "Tolerance" "~"
			(at 236.22 231.14 0)
			(effects
				(font
					(size 1.27 1.27)
				)
				(justify left bottom)
				(hide yes)
			)
		)
		(property "Current" "1A"
			(at 236.22 251.46 0)
			(effects
				(font
					(size 1.27 1.27)
					(thickness 0.15)
				)
				(justify left bottom)
				(hide yes)
			)
		)
		(property "Public" "False"
			(at 236.22 251.46 0)
			(effects
				(font
					(size 1.27 1.27)
				)
				(justify left bottom)
				(hide yes)
			)
		)
		(pin "1"
		)
		(pin "2"
		)
		(instances
			(project "jetson-orin-baseboard-oculink-expansion"
				(path ""
					(reference "R37")
					(unit 1)
				)
			)
		)
	)
	(symbol
		(lib_id "antmicroResistors0402:R_1k_0402")
		(at 162.56 130.81 90)
		(unit 1)
		(exclude_from_sim no)
		(in_bom yes)
		(on_board yes)
		(dnp yes)
		(property "Reference" "R30"
			(at 162.56 134.62 0)
			(effects
				(font
					(size 1.27 1.27)
					(thickness 0.15)
				)
				(justify right)
			)
		)
		(property "Value" "R_1k_0402"
			(at 175.26 110.49 0)
			(effects
				(font
					(size 1.27 1.27)
					(thickness 0.15)
				)
				(justify left bottom)
				(hide yes)
			)
		)
		(property "Footprint" "antmicro-footprints:R_0402_1005Metric"
			(at 177.8 110.49 0)
			(effects
				(font
					(size 1.27 1.27)
					(thickness 0.15)
				)
				(justify left bottom)
				(hide yes)
			)
		)
		(property "Datasheet" "https://www.bourns.com/docs/product-datasheets/cr.pdf"
			(at 180.34 110.49 0)
			(effects
				(font
					(size 1.27 1.27)
					(thickness 0.15)
				)
				(justify left bottom)
				(hide yes)
			)
		)
		(property "Description" "SMD Chip Resistor, 1 kohm, ± 1%, 63 mW, 0402 [1005 Metric], Thick Film, General Purpose"
			(at 162.56 130.81 0)
			(effects
				(font
					(size 1.27 1.27)
				)
				(hide yes)
			)
		)
		(property "MPN" "CR0402-FX-1001GLF"
			(at 182.88 110.49 0)
			(effects
				(font
					(size 1.27 1.27)
					(thickness 0.15)
				)
				(justify left bottom)
				(hide yes)
			)
		)
		(property "Manufacturer" "Bourns"
			(at 185.42 110.49 0)
			(effects
				(font
					(size 1.27 1.27)
					(thickness 0.15)
				)
				(justify left bottom)
				(hide yes)
			)
		)
		(property "License" "Apache-2.0"
			(at 187.96 110.49 0)
			(effects
				(font
					(size 1.27 1.27)
					(thickness 0.15)
				)
				(justify left bottom)
				(hide yes)
			)
		)
		(property "Author" "Antmicro"
			(at 190.5 110.49 0)
			(effects
				(font
					(size 1.27 1.27)
					(thickness 0.15)
				)
				(justify left bottom)
				(hide yes)
			)
		)
		(property "Val" "1k"
			(at 161.29 130.81 0)
			(effects
				(font
					(size 1.27 1.27)
					(thickness 0.15)
				)
				(justify right)
			)
		)
		(property "Tolerance" "1%"
			(at 172.72 110.49 0)
			(effects
				(font
					(size 1.27 1.27)
				)
				(justify left bottom)
				(hide yes)
			)
		)
		(property "Public" "False"
			(at 193.04 110.49 0)
			(effects
				(font
					(size 1.27 1.27)
				)
				(justify left bottom)
				(hide yes)
			)
		)
		(pin "1"
		)
		(pin "2"
		)
		(instances
			(project "jetson-orin-baseboard-oculink-expansion"
				(path ""
					(reference "R30")
					(unit 1)
				)
			)
		)
	)
	(symbol
		(lib_id "antmicropower:GND")
		(at 182.88 49.53 0)
		(unit 1)
		(exclude_from_sim no)
		(in_bom yes)
		(on_board yes)
		(dnp no)
		(property "Reference" "#PWR052"
			(at 191.77 52.07 0)
			(effects
				(font
					(size 1.27 1.27)
					(thickness 0.15)
				)
				(justify left bottom)
				(hide yes)
			)
		)
		(property "Value" "GND"
			(at 182.88 53.34 0)
			(effects
				(font
					(size 1.27 1.27)
					(thickness 0.15)
				)
			)
		)
		(property "Footprint" ""
			(at 191.77 57.15 0)
			(effects
				(font
					(size 1.27 1.27)
					(thickness 0.15)
				)
				(justify left bottom)
				(hide yes)
			)
		)
		(property "Datasheet" ""
			(at 191.77 62.23 0)
			(effects
				(font
					(size 1.27 1.27)
					(thickness 0.15)
				)
				(justify left bottom)
				(hide yes)
			)
		)
		(property "Description" ""
			(at 182.88 49.53 0)
			(effects
				(font
					(size 1.27 1.27)
				)
				(hide yes)
			)
		)
		(property "Author" "Antmicro"
			(at 191.77 57.15 0)
			(effects
				(font
					(size 1.27 1.27)
					(thickness 0.15)
				)
				(justify left bottom)
				(hide yes)
			)
		)
		(property "License" "Apache-2.0"
			(at 191.77 59.69 0)
			(effects
				(font
					(size 1.27 1.27)
					(thickness 0.15)
				)
				(justify left bottom)
				(hide yes)
			)
		)
		(pin "1"
		)
		(instances
			(project "jetson-orin-baseboard-oculink-expansion"
				(path ""
					(reference "#PWR052")
					(unit 1)
				)
			)
		)
	)
	(symbol
		(lib_id "antmicropower:+3V3")
		(at 179.07 71.12 0)
		(mirror y)
		(unit 1)
		(exclude_from_sim no)
		(in_bom yes)
		(on_board yes)
		(dnp no)
		(property "Reference" "#PWR060"
			(at 163.83 71.12 0)
			(effects
				(font
					(size 1.27 1.27)
					(thickness 0.15)
				)
				(justify left bottom)
				(hide yes)
			)
		)
		(property "Value" "+3V3"
			(at 179.07 66.04 0)
			(effects
				(font
					(size 1.27 1.27)
					(thickness 0.15)
				)
			)
		)
		(property "Footprint" ""
			(at 163.83 78.74 0)
			(effects
				(font
					(size 1.27 1.27)
					(thickness 0.15)
				)
				(justify left bottom)
				(hide yes)
			)
		)
		(property "Datasheet" ""
			(at 163.83 81.28 0)
			(effects
				(font
					(size 1.27 1.27)
					(thickness 0.15)
				)
				(justify left bottom)
				(hide yes)
			)
		)
		(property "Description" ""
			(at 179.07 71.12 0)
			(effects
				(font
					(size 1.27 1.27)
				)
				(hide yes)
			)
		)
		(property "Author" "Antmicro"
			(at 163.83 73.66 0)
			(effects
				(font
					(size 1.27 1.27)
					(thickness 0.15)
				)
				(justify left bottom)
				(hide yes)
			)
		)
		(property "License" "Apache-2.0"
			(at 163.83 76.2 0)
			(effects
				(font
					(size 1.27 1.27)
					(thickness 0.15)
				)
				(justify left bottom)
				(hide yes)
			)
		)
		(pin "1"
		)
		(instances
			(project "jetson-orin-baseboard-oculink-expansion"
				(path ""
					(reference "#PWR060")
					(unit 1)
				)
			)
		)
	)
	(symbol
		(lib_id "antmicroCapacitors0402:C_100n_0402")
		(at 165.1 34.29 90)
		(unit 1)
		(exclude_from_sim no)
		(in_bom yes)
		(on_board yes)
		(dnp no)
		(fields_autoplaced yes)
		(property "Reference" "C21"
			(at 167.64 30.4736 90)
			(effects
				(font
					(size 1.27 1.27)
					(thickness 0.15)
				)
				(justify right)
			)
		)
		(property "Value" "C_100n_0402"
			(at 175.26 13.97 0)
			(effects
				(font
					(size 1.27 1.27)
					(thickness 0.15)
				)
				(justify left bottom)
				(hide yes)
			)
		)
		(property "Footprint" "antmicro-footprints:C_0402_1005Metric"
			(at 177.8 13.97 0)
			(effects
				(font
					(size 1.27 1.27)
					(thickness 0.15)
				)
				(justify left bottom)
				(hide yes)
			)
		)
		(property "Datasheet" "https://www.murata.com/products/productdetail?partno=GRM155R61H104KE14%23"
			(at 180.34 13.97 0)
			(effects
				(font
					(size 1.27 1.27)
					(thickness 0.15)
				)
				(justify left bottom)
				(hide yes)
			)
		)
		(property "Description" "SMD Multilayer Ceramic Capacitor, 0.1 µF, 50 V, 0402 [1005 Metric], ± 10%, X5R, GRM Series"
			(at 165.1 34.29 0)
			(effects
				(font
					(size 1.27 1.27)
				)
				(hide yes)
			)
		)
		(property "MPN" "GRM155R61H104KE14D"
			(at 182.88 13.97 0)
			(effects
				(font
					(size 1.27 1.27)
					(thickness 0.15)
				)
				(justify left bottom)
				(hide yes)
			)
		)
		(property "Manufacturer" "Murata"
			(at 185.42 13.97 0)
			(effects
				(font
					(size 1.27 1.27)
					(thickness 0.15)
				)
				(justify left bottom)
				(hide yes)
			)
		)
		(property "License" "Apache-2.0"
			(at 187.96 13.97 0)
			(effects
				(font
					(size 1.27 1.27)
					(thickness 0.15)
				)
				(justify left bottom)
				(hide yes)
			)
		)
		(property "Author" "Antmicro"
			(at 190.5 13.97 0)
			(effects
				(font
					(size 1.27 1.27)
					(thickness 0.15)
				)
				(justify left bottom)
				(hide yes)
			)
		)
		(property "Val" "100n"
			(at 167.64 33.0136 90)
			(effects
				(font
					(size 1.27 1.27)
					(thickness 0.15)
				)
				(justify right)
			)
		)
		(property "Voltage" "50V"
			(at 193.04 13.97 0)
			(effects
				(font
					(size 1.27 1.27)
				)
				(justify left bottom)
				(hide yes)
			)
		)
		(property "Dielectric" "X5R"
			(at 195.58 13.97 0)
			(effects
				(font
					(size 1.27 1.27)
				)
				(justify left bottom)
				(hide yes)
			)
		)
		(property "Public" "False"
			(at 198.12 13.97 0)
			(effects
				(font
					(size 1.27 1.27)
				)
				(justify left bottom)
				(hide yes)
			)
		)
		(pin "1"
		)
		(pin "2"
		)
		(instances
			(project "jetson-orin-baseboard-oculink-expansion"
				(path ""
					(reference "C21")
					(unit 1)
				)
			)
		)
	)
	(symbol
		(lib_id "antmicropower:+3V3")
		(at 173.99 90.17 0)
		(unit 1)
		(exclude_from_sim no)
		(in_bom yes)
		(on_board yes)
		(dnp no)
		(property "Reference" "#PWR057"
			(at 189.23 90.17 0)
			(effects
				(font
					(size 1.27 1.27)
					(thickness 0.15)
				)
				(justify left bottom)
				(hide yes)
			)
		)
		(property "Value" "+3V3"
			(at 170.18 88.9 0)
			(effects
				(font
					(size 1.27 1.27)
					(thickness 0.15)
				)
			)
		)
		(property "Footprint" ""
			(at 189.23 97.79 0)
			(effects
				(font
					(size 1.27 1.27)
					(thickness 0.15)
				)
				(justify left bottom)
				(hide yes)
			)
		)
		(property "Datasheet" ""
			(at 189.23 100.33 0)
			(effects
				(font
					(size 1.27 1.27)
					(thickness 0.15)
				)
				(justify left bottom)
				(hide yes)
			)
		)
		(property "Description" ""
			(at 173.99 90.17 0)
			(effects
				(font
					(size 1.27 1.27)
				)
				(hide yes)
			)
		)
		(property "Author" "Antmicro"
			(at 189.23 92.71 0)
			(effects
				(font
					(size 1.27 1.27)
					(thickness 0.15)
				)
				(justify left bottom)
				(hide yes)
			)
		)
		(property "License" "Apache-2.0"
			(at 189.23 95.25 0)
			(effects
				(font
					(size 1.27 1.27)
					(thickness 0.15)
				)
				(justify left bottom)
				(hide yes)
			)
		)
		(pin "1"
		)
		(instances
			(project "jetson-orin-baseboard-oculink-expansion"
				(path ""
					(reference "#PWR057")
					(unit 1)
				)
			)
		)
	)
	(symbol
		(lib_id "antmicropower:+3.3V")
		(at 242.57 115.57 0)
		(mirror y)
		(unit 1)
		(exclude_from_sim no)
		(in_bom yes)
		(on_board yes)
		(dnp no)
		(property "Reference" "#PWR023"
			(at 242.57 119.38 0)
			(effects
				(font
					(size 1.27 1.27)
				)
				(hide yes)
			)
		)
		(property "Value" "+3V3"
			(at 242.57 110.49 0)
			(effects
				(font
					(size 1.27 1.27)
				)
			)
		)
		(property "Footprint" ""
			(at 242.57 115.57 0)
			(effects
				(font
					(size 1.27 1.27)
				)
				(hide yes)
			)
		)
		(property "Datasheet" ""
			(at 242.57 115.57 0)
			(effects
				(font
					(size 1.27 1.27)
				)
				(hide yes)
			)
		)
		(property "Description" ""
			(at 242.57 115.57 0)
			(effects
				(font
					(size 1.27 1.27)
				)
				(hide yes)
			)
		)
		(pin "1"
		)
		(instances
			(project "jetson-orin-baseboard-oculink-expansion"
				(path ""
					(reference "#PWR023")
					(unit 1)
				)
			)
		)
	)
	(symbol
		(lib_id "antmicroCapacitors0402:C_100n_0402")
		(at 173.99 49.53 90)
		(unit 1)
		(exclude_from_sim no)
		(in_bom yes)
		(on_board yes)
		(dnp no)
		(fields_autoplaced yes)
		(property "Reference" "C26"
			(at 176.53 45.7136 90)
			(effects
				(font
					(size 1.27 1.27)
					(thickness 0.15)
				)
				(justify right)
			)
		)
		(property "Value" "C_100n_0402"
			(at 184.15 29.21 0)
			(effects
				(font
					(size 1.27 1.27)
					(thickness 0.15)
				)
				(justify left bottom)
				(hide yes)
			)
		)
		(property "Footprint" "antmicro-footprints:C_0402_1005Metric"
			(at 186.69 29.21 0)
			(effects
				(font
					(size 1.27 1.27)
					(thickness 0.15)
				)
				(justify left bottom)
				(hide yes)
			)
		)
		(property "Datasheet" "https://www.murata.com/products/productdetail?partno=GRM155R61H104KE14%23"
			(at 189.23 29.21 0)
			(effects
				(font
					(size 1.27 1.27)
					(thickness 0.15)
				)
				(justify left bottom)
				(hide yes)
			)
		)
		(property "Description" "SMD Multilayer Ceramic Capacitor, 0.1 µF, 50 V, 0402 [1005 Metric], ± 10%, X5R, GRM Series"
			(at 173.99 49.53 0)
			(effects
				(font
					(size 1.27 1.27)
				)
				(hide yes)
			)
		)
		(property "MPN" "GRM155R61H104KE14D"
			(at 191.77 29.21 0)
			(effects
				(font
					(size 1.27 1.27)
					(thickness 0.15)
				)
				(justify left bottom)
				(hide yes)
			)
		)
		(property "Manufacturer" "Murata"
			(at 194.31 29.21 0)
			(effects
				(font
					(size 1.27 1.27)
					(thickness 0.15)
				)
				(justify left bottom)
				(hide yes)
			)
		)
		(property "License" "Apache-2.0"
			(at 196.85 29.21 0)
			(effects
				(font
					(size 1.27 1.27)
					(thickness 0.15)
				)
				(justify left bottom)
				(hide yes)
			)
		)
		(property "Author" "Antmicro"
			(at 199.39 29.21 0)
			(effects
				(font
					(size 1.27 1.27)
					(thickness 0.15)
				)
				(justify left bottom)
				(hide yes)
			)
		)
		(property "Val" "100n"
			(at 176.53 48.2536 90)
			(effects
				(font
					(size 1.27 1.27)
					(thickness 0.15)
				)
				(justify right)
			)
		)
		(property "Voltage" "50V"
			(at 201.93 29.21 0)
			(effects
				(font
					(size 1.27 1.27)
				)
				(justify left bottom)
				(hide yes)
			)
		)
		(property "Dielectric" "X5R"
			(at 204.47 29.21 0)
			(effects
				(font
					(size 1.27 1.27)
				)
				(justify left bottom)
				(hide yes)
			)
		)
		(property "Public" "False"
			(at 207.01 29.21 0)
			(effects
				(font
					(size 1.27 1.27)
				)
				(justify left bottom)
				(hide yes)
			)
		)
		(pin "1"
		)
		(pin "2"
		)
		(instances
			(project "jetson-orin-baseboard-oculink-expansion"
				(path ""
					(reference "C26")
					(unit 1)
				)
			)
		)
	)
	(symbol
		(lib_id "antmicroResistors0402:R_1k_0402")
		(at 149.86 101.6 270)
		(unit 1)
		(exclude_from_sim no)
		(in_bom yes)
		(on_board yes)
		(dnp yes)
		(property "Reference" "R17"
			(at 149.86 97.79 0)
			(effects
				(font
					(size 1.27 1.27)
					(thickness 0.15)
				)
				(justify right)
			)
		)
		(property "Value" "R_1k_0402"
			(at 137.16 121.92 0)
			(effects
				(font
					(size 1.27 1.27)
					(thickness 0.15)
				)
				(justify left bottom)
				(hide yes)
			)
		)
		(property "Footprint" "antmicro-footprints:R_0402_1005Metric"
			(at 134.62 121.92 0)
			(effects
				(font
					(size 1.27 1.27)
					(thickness 0.15)
				)
				(justify left bottom)
				(hide yes)
			)
		)
		(property "Datasheet" "https://www.bourns.com/docs/product-datasheets/cr.pdf"
			(at 132.08 121.92 0)
			(effects
				(font
					(size 1.27 1.27)
					(thickness 0.15)
				)
				(justify left bottom)
				(hide yes)
			)
		)
		(property "Description" "SMD Chip Resistor, 1 kohm, ± 1%, 63 mW, 0402 [1005 Metric], Thick Film, General Purpose"
			(at 149.86 101.6 0)
			(effects
				(font
					(size 1.27 1.27)
				)
				(hide yes)
			)
		)
		(property "MPN" "CR0402-FX-1001GLF"
			(at 129.54 121.92 0)
			(effects
				(font
					(size 1.27 1.27)
					(thickness 0.15)
				)
				(justify left bottom)
				(hide yes)
			)
		)
		(property "Manufacturer" "Bourns"
			(at 127 121.92 0)
			(effects
				(font
					(size 1.27 1.27)
					(thickness 0.15)
				)
				(justify left bottom)
				(hide yes)
			)
		)
		(property "License" "Apache-2.0"
			(at 124.46 121.92 0)
			(effects
				(font
					(size 1.27 1.27)
					(thickness 0.15)
				)
				(justify left bottom)
				(hide yes)
			)
		)
		(property "Author" "Antmicro"
			(at 121.92 121.92 0)
			(effects
				(font
					(size 1.27 1.27)
					(thickness 0.15)
				)
				(justify left bottom)
				(hide yes)
			)
		)
		(property "Val" "1k"
			(at 151.13 101.6 0)
			(effects
				(font
					(size 1.27 1.27)
					(thickness 0.15)
				)
				(justify right)
			)
		)
		(property "Tolerance" "1%"
			(at 139.7 121.92 0)
			(effects
				(font
					(size 1.27 1.27)
				)
				(justify left bottom)
				(hide yes)
			)
		)
		(property "Public" "False"
			(at 119.38 121.92 0)
			(effects
				(font
					(size 1.27 1.27)
				)
				(justify left bottom)
				(hide yes)
			)
		)
		(pin "1"
		)
		(pin "2"
		)
		(instances
			(project "jetson-orin-baseboard-oculink-expansion"
				(path ""
					(reference "R17")
					(unit 1)
				)
			)
		)
	)
	(symbol
		(lib_id "antmicropower:GND")
		(at 373.38 137.16 0)
		(unit 1)
		(exclude_from_sim no)
		(in_bom yes)
		(on_board yes)
		(dnp no)
		(fields_autoplaced yes)
		(property "Reference" "#PWR03"
			(at 373.38 143.51 0)
			(effects
				(font
					(size 1.27 1.27)
				)
				(justify left bottom)
				(hide yes)
			)
		)
		(property "Value" "GND"
			(at 373.38 140.97 0)
			(effects
				(font
					(size 1.27 1.27)
					(thickness 0.15)
				)
			)
		)
		(property "Footprint" ""
			(at 382.27 144.78 0)
			(effects
				(font
					(size 1.27 1.27)
					(thickness 0.15)
				)
				(justify left bottom)
				(hide yes)
			)
		)
		(property "Datasheet" ""
			(at 382.27 149.86 0)
			(effects
				(font
					(size 1.27 1.27)
					(thickness 0.15)
				)
				(justify left bottom)
				(hide yes)
			)
		)
		(property "Description" ""
			(at 373.38 137.16 0)
			(effects
				(font
					(size 1.27 1.27)
				)
				(hide yes)
			)
		)
		(property "Author" "Antmicro"
			(at 382.27 144.78 0)
			(effects
				(font
					(size 1.27 1.27)
					(thickness 0.15)
				)
				(justify left bottom)
				(hide yes)
			)
		)
		(property "License" "Apache-2.0"
			(at 382.27 147.32 0)
			(effects
				(font
					(size 1.27 1.27)
					(thickness 0.15)
				)
				(justify left bottom)
				(hide yes)
			)
		)
		(pin "1"
		)
		(instances
			(project "jetson-orin-baseboard-oculink-expansion"
				(path ""
					(reference "#PWR03")
					(unit 1)
				)
			)
		)
	)
	(symbol
		(lib_id "antmicroResistors0402:R_11k3_0402")
		(at 281.94 175.26 90)
		(unit 1)
		(exclude_from_sim no)
		(in_bom yes)
		(on_board yes)
		(dnp no)
		(property "Reference" "R48"
			(at 283.21 171.45 90)
			(effects
				(font
					(size 1.27 1.27)
					(thickness 0.15)
				)
				(justify right)
			)
		)
		(property "Value" "R_11k3_0402"
			(at 294.64 154.94 0)
			(effects
				(font
					(size 1.27 1.27)
					(thickness 0.15)
				)
				(justify left bottom)
				(hide yes)
			)
		)
		(property "Footprint" "antmicro-footprints:R_0402_1005Metric"
			(at 297.18 154.94 0)
			(effects
				(font
					(size 1.27 1.27)
					(thickness 0.15)
				)
				(justify left bottom)
				(hide yes)
			)
		)
		(property "Datasheet" "https://www.bourns.com/docs/product-datasheets/cr.pdf"
			(at 299.72 154.94 0)
			(effects
				(font
					(size 1.27 1.27)
					(thickness 0.15)
				)
				(justify left bottom)
				(hide yes)
			)
		)
		(property "Description" "SMD Chip Resistor, 11.3 kohm, ± 1%, 62.5 mW, 0402 [1005 Metric], Thick Film, General Purpose"
			(at 281.94 175.26 0)
			(effects
				(font
					(size 1.27 1.27)
				)
				(hide yes)
			)
		)
		(property "MPN" "CR0402-FX-1132GLF"
			(at 302.26 154.94 0)
			(effects
				(font
					(size 1.27 1.27)
					(thickness 0.15)
				)
				(justify left bottom)
				(hide yes)
			)
		)
		(property "Manufacturer" "Bourns"
			(at 304.8 154.94 0)
			(effects
				(font
					(size 1.27 1.27)
					(thickness 0.15)
				)
				(justify left bottom)
				(hide yes)
			)
		)
		(property "License" "Apache-2.0"
			(at 307.34 154.94 0)
			(effects
				(font
					(size 1.27 1.27)
					(thickness 0.15)
				)
				(justify left bottom)
				(hide yes)
			)
		)
		(property "Author" "Antmicro"
			(at 309.88 154.94 0)
			(effects
				(font
					(size 1.27 1.27)
					(thickness 0.15)
				)
				(justify left bottom)
				(hide yes)
			)
		)
		(property "Val" "11k3"
			(at 283.21 173.99 90)
			(effects
				(font
					(size 1.27 1.27)
					(thickness 0.15)
				)
				(justify right)
			)
		)
		(property "Tolerance" "1%"
			(at 292.1 154.94 0)
			(effects
				(font
					(size 1.27 1.27)
				)
				(justify left bottom)
				(hide yes)
			)
		)
		(pin "1"
		)
		(pin "2"
		)
		(instances
			(project ""
				(path ""
					(reference "R48")
					(unit 1)
				)
			)
		)
	)
	(symbol
		(lib_id "antmicroResistors0402:R_10k_0402")
		(at 250.19 162.56 270)
		(unit 1)
		(exclude_from_sim no)
		(in_bom yes)
		(on_board yes)
		(dnp no)
		(property "Reference" "R47"
			(at 251.46 163.83 90)
			(effects
				(font
					(size 1.27 1.27)
					(thickness 0.15)
				)
				(justify left)
			)
		)
		(property "Value" "R_10k_0402"
			(at 237.49 182.88 0)
			(effects
				(font
					(size 1.27 1.27)
					(thickness 0.15)
				)
				(justify left bottom)
				(hide yes)
			)
		)
		(property "Footprint" "antmicro-footprints:R_0402_1005Metric"
			(at 234.95 182.88 0)
			(effects
				(font
					(size 1.27 1.27)
					(thickness 0.15)
				)
				(justify left bottom)
				(hide yes)
			)
		)
		(property "Datasheet" "https://www.bourns.com/docs/product-datasheets/cr.pdf"
			(at 232.41 182.88 0)
			(effects
				(font
					(size 1.27 1.27)
					(thickness 0.15)
				)
				(justify left bottom)
				(hide yes)
			)
		)
		(property "Description" "SMD Chip Resistor, 10 kohm, ± 1%, 62.5 mW, 0402 [1005 Metric], Thick Film, General Purpose"
			(at 250.19 162.56 0)
			(effects
				(font
					(size 1.27 1.27)
				)
				(hide yes)
			)
		)
		(property "MPN" "CR0402-FX-1002GLF"
			(at 229.87 182.88 0)
			(effects
				(font
					(size 1.27 1.27)
					(thickness 0.15)
				)
				(justify left bottom)
				(hide yes)
			)
		)
		(property "Manufacturer" "Bourns"
			(at 227.33 182.88 0)
			(effects
				(font
					(size 1.27 1.27)
					(thickness 0.15)
				)
				(justify left bottom)
				(hide yes)
			)
		)
		(property "License" "Apache-2.0"
			(at 224.79 182.88 0)
			(effects
				(font
					(size 1.27 1.27)
					(thickness 0.15)
				)
				(justify left bottom)
				(hide yes)
			)
		)
		(property "Author" "Antmicro"
			(at 222.25 182.88 0)
			(effects
				(font
					(size 1.27 1.27)
					(thickness 0.15)
				)
				(justify left bottom)
				(hide yes)
			)
		)
		(property "Val" "10k"
			(at 251.46 166.37 90)
			(effects
				(font
					(size 1.27 1.27)
					(thickness 0.15)
				)
				(justify left)
			)
		)
		(property "Tolerance" "1%"
			(at 240.03 182.88 0)
			(effects
				(font
					(size 1.27 1.27)
				)
				(justify left bottom)
				(hide yes)
			)
		)
		(pin "1"
		)
		(pin "2"
		)
		(instances
			(project "jetson-orin-baseboard-oculink-expansion"
				(path ""
					(reference "R47")
					(unit 1)
				)
			)
		)
	)
	(symbol
		(lib_id "antmicropower:GND")
		(at 281.94 176.53 0)
		(mirror y)
		(unit 1)
		(exclude_from_sim no)
		(in_bom yes)
		(on_board yes)
		(dnp no)
		(property "Reference" "#PWR068"
			(at 273.05 179.07 0)
			(effects
				(font
					(size 1.27 1.27)
					(thickness 0.15)
				)
				(justify left bottom)
				(hide yes)
			)
		)
		(property "Value" "GND"
			(at 281.94 180.34 0)
			(effects
				(font
					(size 1.27 1.27)
					(thickness 0.15)
				)
			)
		)
		(property "Footprint" ""
			(at 273.05 184.15 0)
			(effects
				(font
					(size 1.27 1.27)
					(thickness 0.15)
				)
				(justify left bottom)
				(hide yes)
			)
		)
		(property "Datasheet" ""
			(at 273.05 189.23 0)
			(effects
				(font
					(size 1.27 1.27)
					(thickness 0.15)
				)
				(justify left bottom)
				(hide yes)
			)
		)
		(property "Description" ""
			(at 281.94 176.53 0)
			(effects
				(font
					(size 1.27 1.27)
				)
				(hide yes)
			)
		)
		(property "Author" "Antmicro"
			(at 273.05 184.15 0)
			(effects
				(font
					(size 1.27 1.27)
					(thickness 0.15)
				)
				(justify left bottom)
				(hide yes)
			)
		)
		(property "License" "Apache-2.0"
			(at 273.05 186.69 0)
			(effects
				(font
					(size 1.27 1.27)
					(thickness 0.15)
				)
				(justify left bottom)
				(hide yes)
			)
		)
		(pin "1"
		)
		(instances
			(project "jetson-orin-baseboard-oculink-expansion"
				(path ""
					(reference "#PWR068")
					(unit 1)
				)
			)
		)
	)
	(symbol
		(lib_id "antmicropower:GND")
		(at 198.12 265.43 0)
		(mirror y)
		(unit 1)
		(exclude_from_sim no)
		(in_bom yes)
		(on_board yes)
		(dnp no)
		(property "Reference" "#PWR050"
			(at 189.23 267.97 0)
			(effects
				(font
					(size 1.27 1.27)
					(thickness 0.15)
				)
				(justify left bottom)
				(hide yes)
			)
		)
		(property "Value" "GND"
			(at 198.12 269.24 0)
			(effects
				(font
					(size 1.27 1.27)
					(thickness 0.15)
				)
			)
		)
		(property "Footprint" ""
			(at 189.23 273.05 0)
			(effects
				(font
					(size 1.27 1.27)
					(thickness 0.15)
				)
				(justify left bottom)
				(hide yes)
			)
		)
		(property "Datasheet" ""
			(at 189.23 278.13 0)
			(effects
				(font
					(size 1.27 1.27)
					(thickness 0.15)
				)
				(justify left bottom)
				(hide yes)
			)
		)
		(property "Description" ""
			(at 198.12 265.43 0)
			(effects
				(font
					(size 1.27 1.27)
				)
				(hide yes)
			)
		)
		(property "Author" "Antmicro"
			(at 189.23 273.05 0)
			(effects
				(font
					(size 1.27 1.27)
					(thickness 0.15)
				)
				(justify left bottom)
				(hide yes)
			)
		)
		(property "License" "Apache-2.0"
			(at 189.23 275.59 0)
			(effects
				(font
					(size 1.27 1.27)
					(thickness 0.15)
				)
				(justify left bottom)
				(hide yes)
			)
		)
		(pin "1"
		)
		(instances
			(project "jetson-orin-baseboard-oculink-expansion"
				(path ""
					(reference "#PWR050")
					(unit 1)
				)
			)
		)
	)
	(symbol
		(lib_id "antmicropower:GND")
		(at 156.21 34.29 0)
		(unit 1)
		(exclude_from_sim no)
		(in_bom yes)
		(on_board yes)
		(dnp no)
		(property "Reference" "#PWR037"
			(at 165.1 36.83 0)
			(effects
				(font
					(size 1.27 1.27)
					(thickness 0.15)
				)
				(justify left bottom)
				(hide yes)
			)
		)
		(property "Value" "GND"
			(at 156.21 38.1 0)
			(effects
				(font
					(size 1.27 1.27)
					(thickness 0.15)
				)
			)
		)
		(property "Footprint" ""
			(at 165.1 41.91 0)
			(effects
				(font
					(size 1.27 1.27)
					(thickness 0.15)
				)
				(justify left bottom)
				(hide yes)
			)
		)
		(property "Datasheet" ""
			(at 165.1 46.99 0)
			(effects
				(font
					(size 1.27 1.27)
					(thickness 0.15)
				)
				(justify left bottom)
				(hide yes)
			)
		)
		(property "Description" ""
			(at 156.21 34.29 0)
			(effects
				(font
					(size 1.27 1.27)
				)
				(hide yes)
			)
		)
		(property "Author" "Antmicro"
			(at 165.1 41.91 0)
			(effects
				(font
					(size 1.27 1.27)
					(thickness 0.15)
				)
				(justify left bottom)
				(hide yes)
			)
		)
		(property "License" "Apache-2.0"
			(at 165.1 44.45 0)
			(effects
				(font
					(size 1.27 1.27)
					(thickness 0.15)
				)
				(justify left bottom)
				(hide yes)
			)
		)
		(pin "1"
		)
		(instances
			(project "jetson-orin-baseboard-oculink-expansion"
				(path ""
					(reference "#PWR037")
					(unit 1)
				)
			)
		)
	)
	(symbol
		(lib_id "antmicroCapacitors0402:C_100n_0402")
		(at 172.72 172.72 270)
		(mirror x)
		(unit 1)
		(exclude_from_sim no)
		(in_bom yes)
		(on_board yes)
		(dnp no)
		(fields_autoplaced yes)
		(property "Reference" "C9"
			(at 170.18 168.9036 90)
			(effects
				(font
					(size 1.27 1.27)
					(thickness 0.15)
				)
				(justify right)
			)
		)
		(property "Value" "C_100n_0402"
			(at 162.56 152.4 0)
			(effects
				(font
					(size 1.27 1.27)
					(thickness 0.15)
				)
				(justify left bottom)
				(hide yes)
			)
		)
		(property "Footprint" "antmicro-footprints:C_0402_1005Metric"
			(at 160.02 152.4 0)
			(effects
				(font
					(size 1.27 1.27)
					(thickness 0.15)
				)
				(justify left bottom)
				(hide yes)
			)
		)
		(property "Datasheet" "https://www.murata.com/products/productdetail?partno=GRM155R61H104KE14%23"
			(at 157.48 152.4 0)
			(effects
				(font
					(size 1.27 1.27)
					(thickness 0.15)
				)
				(justify left bottom)
				(hide yes)
			)
		)
		(property "Description" "SMD Multilayer Ceramic Capacitor, 0.1 µF, 50 V, 0402 [1005 Metric], ± 10%, X5R, GRM Series"
			(at 172.72 172.72 0)
			(effects
				(font
					(size 1.27 1.27)
				)
				(hide yes)
			)
		)
		(property "MPN" "GRM155R61H104KE14D"
			(at 154.94 152.4 0)
			(effects
				(font
					(size 1.27 1.27)
					(thickness 0.15)
				)
				(justify left bottom)
				(hide yes)
			)
		)
		(property "Manufacturer" "Murata"
			(at 152.4 152.4 0)
			(effects
				(font
					(size 1.27 1.27)
					(thickness 0.15)
				)
				(justify left bottom)
				(hide yes)
			)
		)
		(property "License" "Apache-2.0"
			(at 149.86 152.4 0)
			(effects
				(font
					(size 1.27 1.27)
					(thickness 0.15)
				)
				(justify left bottom)
				(hide yes)
			)
		)
		(property "Author" "Antmicro"
			(at 147.32 152.4 0)
			(effects
				(font
					(size 1.27 1.27)
					(thickness 0.15)
				)
				(justify left bottom)
				(hide yes)
			)
		)
		(property "Val" "100n"
			(at 170.18 171.4436 90)
			(effects
				(font
					(size 1.27 1.27)
					(thickness 0.15)
				)
				(justify right)
			)
		)
		(property "Voltage" "50V"
			(at 144.78 152.4 0)
			(effects
				(font
					(size 1.27 1.27)
				)
				(justify left bottom)
				(hide yes)
			)
		)
		(property "Dielectric" "X5R"
			(at 142.24 152.4 0)
			(effects
				(font
					(size 1.27 1.27)
				)
				(justify left bottom)
				(hide yes)
			)
		)
		(property "Public" "False"
			(at 139.7 152.4 0)
			(effects
				(font
					(size 1.27 1.27)
				)
				(justify left bottom)
				(hide yes)
			)
		)
		(pin "1"
		)
		(pin "2"
		)
		(instances
			(project "jetson-orin-baseboard-oculink-expansion"
				(path ""
					(reference "C9")
					(unit 1)
				)
			)
		)
	)
	(symbol
		(lib_id "antmicropower:GND")
		(at 147.32 135.89 0)
		(unit 1)
		(exclude_from_sim no)
		(in_bom yes)
		(on_board yes)
		(dnp no)
		(property "Reference" "#PWR043"
			(at 156.21 138.43 0)
			(effects
				(font
					(size 1.27 1.27)
					(thickness 0.15)
				)
				(justify left bottom)
				(hide yes)
			)
		)
		(property "Value" "GND"
			(at 147.32 139.7 0)
			(effects
				(font
					(size 1.27 1.27)
					(thickness 0.15)
				)
			)
		)
		(property "Footprint" ""
			(at 156.21 143.51 0)
			(effects
				(font
					(size 1.27 1.27)
					(thickness 0.15)
				)
				(justify left bottom)
				(hide yes)
			)
		)
		(property "Datasheet" ""
			(at 156.21 148.59 0)
			(effects
				(font
					(size 1.27 1.27)
					(thickness 0.15)
				)
				(justify left bottom)
				(hide yes)
			)
		)
		(property "Description" ""
			(at 147.32 135.89 0)
			(effects
				(font
					(size 1.27 1.27)
				)
				(hide yes)
			)
		)
		(property "Author" "Antmicro"
			(at 156.21 143.51 0)
			(effects
				(font
					(size 1.27 1.27)
					(thickness 0.15)
				)
				(justify left bottom)
				(hide yes)
			)
		)
		(property "License" "Apache-2.0"
			(at 156.21 146.05 0)
			(effects
				(font
					(size 1.27 1.27)
					(thickness 0.15)
				)
				(justify left bottom)
				(hide yes)
			)
		)
		(pin "1"
		)
		(instances
			(project "jetson-orin-baseboard-oculink-expansion"
				(path ""
					(reference "#PWR043")
					(unit 1)
				)
			)
		)
	)
	(symbol
		(lib_id "antmicroInterfaceDriversReceiversTransceivers:PI3EQX16904GL")
		(at 222.25 196.85 0)
		(mirror y)
		(unit 1)
		(exclude_from_sim no)
		(in_bom yes)
		(on_board yes)
		(dnp no)
		(fields_autoplaced yes)
		(property "Reference" "U2"
			(at 210.82 189.23 0)
			(effects
				(font
					(size 1.27 1.27)
					(thickness 0.15)
				)
			)
		)
		(property "Value" "PI3EQX16904GL"
			(at 186.69 207.01 0)
			(effects
				(font
					(size 1.27 1.27)
					(thickness 0.15)
				)
				(justify left bottom)
				(hide yes)
			)
		)
		(property "Footprint" "antmicro-footprints:WQFN-42-1EP_3.5x9mm_P0.5mm"
			(at 186.69 209.55 0)
			(effects
				(font
					(size 1.27 1.27)
					(thickness 0.15)
				)
				(justify left bottom)
				(hide yes)
			)
		)
		(property "Datasheet" "https://www.diodes.com/part/view/PI3EQX16904GL"
			(at 186.69 212.09 0)
			(effects
				(font
					(size 1.27 1.27)
					(thickness 0.15)
				)
				(justify left bottom)
				(hide yes)
			)
		)
		(property "Description" "16Gbps 4-Channel ReDriver with Linear Equalization"
			(at 222.25 196.85 0)
			(effects
				(font
					(size 1.27 1.27)
				)
				(hide yes)
			)
		)
		(property "MPN" "PI3EQX16904GLZHEX"
			(at 210.82 191.77 0)
			(effects
				(font
					(size 1.27 1.27)
					(thickness 0.15)
				)
			)
		)
		(property "Manufacturer" "Diodes Incorporated"
			(at 186.69 204.47 0)
			(effects
				(font
					(size 1.27 1.27)
					(thickness 0.15)
				)
				(justify left bottom)
				(hide yes)
			)
		)
		(property "Author" "Antmicro"
			(at 186.69 214.63 0)
			(effects
				(font
					(size 1.27 1.27)
					(thickness 0.15)
				)
				(justify left bottom)
				(hide yes)
			)
		)
		(property "License" "Apache-2.0"
			(at 186.69 217.17 0)
			(effects
				(font
					(size 1.27 1.27)
					(thickness 0.15)
				)
				(justify left bottom)
				(hide yes)
			)
		)
		(pin "9"
		)
		(pin "29"
		)
		(pin "30"
		)
		(pin "4"
		)
		(pin "20"
		)
		(pin "33"
		)
		(pin "3"
		)
		(pin "19"
		)
		(pin "25"
		)
		(pin "34"
		)
		(pin "31"
		)
		(pin "23"
		)
		(pin "26"
		)
		(pin "27"
		)
		(pin "42"
		)
		(pin "41"
		)
		(pin "24"
		)
		(pin "2"
		)
		(pin "39"
		)
		(pin "28"
		)
		(pin "7"
		)
		(pin "36"
		)
		(pin "43"
		)
		(pin "38"
		)
		(pin "8"
		)
		(pin "5"
		)
		(pin "6"
		)
		(pin "37"
		)
		(pin "40"
		)
		(pin "35"
		)
		(pin "18"
		)
		(pin "21"
		)
		(pin "17"
		)
		(pin "10"
		)
		(pin "1"
		)
		(pin "16"
		)
		(pin "15"
		)
		(pin "14"
		)
		(pin "13"
		)
		(pin "12"
		)
		(pin "11"
		)
		(pin "32"
		)
		(pin "22"
		)
		(instances
			(project "jetson-orin-baseboard-oculink-expansion"
				(path ""
					(reference "U2")
					(unit 1)
				)
			)
		)
	)
	(symbol
		(lib_id "antmicropower:GND")
		(at 57.15 132.08 0)
		(unit 1)
		(exclude_from_sim no)
		(in_bom yes)
		(on_board yes)
		(dnp no)
		(fields_autoplaced yes)
		(property "Reference" "#PWR01"
			(at 57.15 138.43 0)
			(effects
				(font
					(size 1.27 1.27)
				)
				(justify left bottom)
				(hide yes)
			)
		)
		(property "Value" "GND"
			(at 57.15 135.89 0)
			(effects
				(font
					(size 1.27 1.27)
					(thickness 0.15)
				)
			)
		)
		(property "Footprint" ""
			(at 66.04 139.7 0)
			(effects
				(font
					(size 1.27 1.27)
					(thickness 0.15)
				)
				(justify left bottom)
				(hide yes)
			)
		)
		(property "Datasheet" ""
			(at 66.04 144.78 0)
			(effects
				(font
					(size 1.27 1.27)
					(thickness 0.15)
				)
				(justify left bottom)
				(hide yes)
			)
		)
		(property "Description" ""
			(at 57.15 132.08 0)
			(effects
				(font
					(size 1.27 1.27)
				)
				(hide yes)
			)
		)
		(property "Author" "Antmicro"
			(at 66.04 139.7 0)
			(effects
				(font
					(size 1.27 1.27)
					(thickness 0.15)
				)
				(justify left bottom)
				(hide yes)
			)
		)
		(property "License" "Apache-2.0"
			(at 66.04 142.24 0)
			(effects
				(font
					(size 1.27 1.27)
					(thickness 0.15)
				)
				(justify left bottom)
				(hide yes)
			)
		)
		(pin "1"
		)
		(instances
			(project "jetson-orin-baseboard-oculink-expansion"
				(path ""
					(reference "#PWR01")
					(unit 1)
				)
			)
		)
	)
	(symbol
		(lib_id "antmicroMechanicalParts:antmicro_logo")
		(at 45.72 270.51 0)
		(unit 1)
		(exclude_from_sim no)
		(in_bom no)
		(on_board yes)
		(dnp no)
		(fields_autoplaced yes)
		(property "Reference" "N4"
			(at 52.07 268.5262 0)
			(effects
				(font
					(size 1.27 1.27)
					(thickness 0.15)
				)
				(justify left)
			)
		)
		(property "Value" "antmicro_logo"
			(at 52.07 271.0662 0)
			(effects
				(font
					(size 1.27 1.27)
					(thickness 0.15)
				)
				(justify left)
			)
		)
		(property "Footprint" "antmicro-footprints:antmicro-logo_scaled_15mm"
			(at 60.96 280.67 0)
			(effects
				(font
					(size 1.27 1.27)
					(thickness 0.15)
				)
				(justify left bottom)
				(hide yes)
			)
		)
		(property "Datasheet" ""
			(at 60.96 283.21 0)
			(effects
				(font
					(size 1.27 1.27)
					(thickness 0.15)
				)
				(justify left bottom)
				(hide yes)
			)
		)
		(property "Description" "Mechanical part"
			(at 45.72 270.51 0)
			(effects
				(font
					(size 1.27 1.27)
				)
				(hide yes)
			)
		)
		(property "MPN" ""
			(at 45.72 270.51 0)
			(effects
				(font
					(size 1.27 1.27)
				)
			)
		)
		(property "Manufacturer" ""
			(at 60.96 290.83 0)
			(effects
				(font
					(size 1.27 1.27)
					(thickness 0.15)
				)
				(justify left bottom)
				(hide yes)
			)
		)
		(property "Author" "Antmicro"
			(at 60.96 285.75 0)
			(effects
				(font
					(size 1.27 1.27)
					(thickness 0.15)
				)
				(justify left bottom)
				(hide yes)
			)
		)
		(property "License" "Apache-2.0"
			(at 60.96 288.29 0)
			(effects
				(font
					(size 1.27 1.27)
					(thickness 0.15)
				)
				(justify left bottom)
				(hide yes)
			)
		)
		(instances
			(project "jetson-orin-baseboard-oculink-expansion"
				(path ""
					(reference "N4")
					(unit 1)
				)
			)
		)
	)
	(symbol
		(lib_id "antmicroResistors0402:R_1k_0402")
		(at 260.35 240.03 90)
		(mirror x)
		(unit 1)
		(exclude_from_sim no)
		(in_bom yes)
		(on_board yes)
		(dnp no)
		(property "Reference" "R12"
			(at 260.35 236.22 0)
			(effects
				(font
					(size 1.27 1.27)
					(thickness 0.15)
				)
				(justify right)
			)
		)
		(property "Value" "R_1k_0402"
			(at 273.05 260.35 0)
			(effects
				(font
					(size 1.27 1.27)
					(thickness 0.15)
				)
				(justify left bottom)
				(hide yes)
			)
		)
		(property "Footprint" "antmicro-footprints:R_0402_1005Metric"
			(at 275.59 260.35 0)
			(effects
				(font
					(size 1.27 1.27)
					(thickness 0.15)
				)
				(justify left bottom)
				(hide yes)
			)
		)
		(property "Datasheet" "https://www.bourns.com/docs/product-datasheets/cr.pdf"
			(at 278.13 260.35 0)
			(effects
				(font
					(size 1.27 1.27)
					(thickness 0.15)
				)
				(justify left bottom)
				(hide yes)
			)
		)
		(property "Description" "SMD Chip Resistor, 1 kohm, ± 1%, 63 mW, 0402 [1005 Metric], Thick Film, General Purpose"
			(at 260.35 240.03 0)
			(effects
				(font
					(size 1.27 1.27)
				)
				(hide yes)
			)
		)
		(property "MPN" "CR0402-FX-1001GLF"
			(at 280.67 260.35 0)
			(effects
				(font
					(size 1.27 1.27)
					(thickness 0.15)
				)
				(justify left bottom)
				(hide yes)
			)
		)
		(property "Manufacturer" "Bourns"
			(at 283.21 260.35 0)
			(effects
				(font
					(size 1.27 1.27)
					(thickness 0.15)
				)
				(justify left bottom)
				(hide yes)
			)
		)
		(property "License" "Apache-2.0"
			(at 285.75 260.35 0)
			(effects
				(font
					(size 1.27 1.27)
					(thickness 0.15)
				)
				(justify left bottom)
				(hide yes)
			)
		)
		(property "Author" "Antmicro"
			(at 288.29 260.35 0)
			(effects
				(font
					(size 1.27 1.27)
					(thickness 0.15)
				)
				(justify left bottom)
				(hide yes)
			)
		)
		(property "Val" "1k"
			(at 259.08 240.03 0)
			(effects
				(font
					(size 1.27 1.27)
					(thickness 0.15)
				)
				(justify right)
			)
		)
		(property "Tolerance" "1%"
			(at 270.51 260.35 0)
			(effects
				(font
					(size 1.27 1.27)
				)
				(justify left bottom)
				(hide yes)
			)
		)
		(property "Public" "False"
			(at 290.83 260.35 0)
			(effects
				(font
					(size 1.27 1.27)
				)
				(justify left bottom)
				(hide yes)
			)
		)
		(pin "1"
		)
		(pin "2"
		)
		(instances
			(project "jetson-orin-baseboard-oculink-expansion"
				(path ""
					(reference "R12")
					(unit 1)
				)
			)
		)
	)
	(symbol
		(lib_id "antmicroTestPoints:TP_1.5mm_SMD")
		(at 33.02 129.54 180)
		(unit 1)
		(exclude_from_sim no)
		(in_bom no)
		(on_board yes)
		(dnp no)
		(property "Reference" "TP9"
			(at 26.035 129.54 0)
			(effects
				(font
					(size 1.27 1.27)
					(thickness 0.15)
				)
			)
		)
		(property "Value" "TP_1.5mm_SMD"
			(at 17.78 121.92 0)
			(effects
				(font
					(size 1.27 1.27)
					(thickness 0.15)
				)
				(justify left bottom)
				(hide yes)
			)
		)
		(property "Footprint" "antmicro-footprints:TP_SMD_1.5mm"
			(at 17.78 119.38 0)
			(effects
				(font
					(size 1.27 1.27)
					(thickness 0.15)
				)
				(justify left bottom)
				(hide yes)
			)
		)
		(property "Datasheet" ""
			(at 15.24 116.84 0)
			(effects
				(font
					(size 1.27 1.27)
					(thickness 0.15)
				)
				(justify left bottom)
				(hide yes)
			)
		)
		(property "Description" "test point, SMT"
			(at 33.02 129.54 0)
			(effects
				(font
					(size 1.27 1.27)
				)
				(hide yes)
			)
		)
		(property "MPN" ""
			(at 33.02 129.54 0)
			(effects
				(font
					(size 1.27 1.27)
				)
				(hide yes)
			)
		)
		(property "Manufacturer" ""
			(at 33.02 129.54 0)
			(effects
				(font
					(size 1.27 1.27)
				)
				(hide yes)
			)
		)
		(property "Author" "Antmicro"
			(at 17.78 114.3 0)
			(effects
				(font
					(size 1.27 1.27)
					(thickness 0.15)
				)
				(justify left bottom)
				(hide yes)
			)
		)
		(property "License" "Apache-2.0"
			(at 17.78 111.76 0)
			(effects
				(font
					(size 1.27 1.27)
					(thickness 0.15)
				)
				(justify left bottom)
				(hide yes)
			)
		)
		(pin "1"
		)
		(instances
			(project "jetson-orin-baseboard-oculink-expansion"
				(path ""
					(reference "TP9")
					(unit 1)
				)
			)
		)
	)
	(symbol
		(lib_id "antmicroTestPoints:TP_0.75mm_SMD")
		(at 224.79 242.57 0)
		(unit 1)
		(exclude_from_sim no)
		(in_bom no)
		(on_board yes)
		(dnp no)
		(property "Reference" "TP12"
			(at 231.14 242.57 0)
			(effects
				(font
					(size 1.27 1.27)
					(thickness 0.15)
				)
			)
		)
		(property "Value" "TP_0.75mm_SMD"
			(at 235.585 246.38 0)
			(effects
				(font
					(size 1.27 1.27)
					(thickness 0.15)
				)
				(justify left bottom)
				(hide yes)
			)
		)
		(property "Footprint" "antmicro-footprints:TP_SMD_0.75mm"
			(at 235.585 248.92 0)
			(effects
				(font
					(size 1.27 1.27)
					(thickness 0.15)
				)
				(justify left bottom)
				(hide yes)
			)
		)
		(property "Datasheet" ""
			(at 242.57 255.27 0)
			(effects
				(font
					(size 1.27 1.27)
					(thickness 0.15)
				)
				(justify left bottom)
				(hide yes)
			)
		)
		(property "Description" "SMT test point"
			(at 224.79 242.57 0)
			(effects
				(font
					(size 1.27 1.27)
				)
				(hide yes)
			)
		)
		(property "MPN" ""
			(at 235.585 254 0)
			(effects
				(font
					(size 1.27 1.27)
					(thickness 0.15)
				)
				(justify left bottom)
				(hide yes)
			)
		)
		(property "Manufacturer" ""
			(at 235.585 248.92 0)
			(effects
				(font
					(size 1.27 1.27)
					(thickness 0.15)
				)
				(justify left bottom)
				(hide yes)
			)
		)
		(property "Author" "Antmicro"
			(at 235.585 251.46 0)
			(effects
				(font
					(size 1.27 1.27)
					(thickness 0.15)
				)
				(justify left bottom)
				(hide yes)
			)
		)
		(property "License" "Apache-2.0"
			(at 235.585 254 0)
			(effects
				(font
					(size 1.27 1.27)
					(thickness 0.15)
				)
				(justify left bottom)
				(hide yes)
			)
		)
		(property "Public" "False"
			(at 234.95 256.54 0)
			(effects
				(font
					(size 1.27 1.27)
				)
				(justify left bottom)
				(hide yes)
			)
		)
		(pin "1"
		)
		(instances
			(project "jetson-orin-baseboard-oculink-expansion"
				(path ""
					(reference "TP12")
					(unit 1)
				)
			)
		)
	)
	(symbol
		(lib_id "antmicroCapacitors0402:C_100n_0402")
		(at 146.05 187.96 270)
		(mirror x)
		(unit 1)
		(exclude_from_sim no)
		(in_bom yes)
		(on_board yes)
		(dnp no)
		(fields_autoplaced yes)
		(property "Reference" "C28"
			(at 143.51 184.1436 90)
			(effects
				(font
					(size 1.27 1.27)
					(thickness 0.15)
				)
				(justify right)
			)
		)
		(property "Value" "C_100n_0402"
			(at 135.89 167.64 0)
			(effects
				(font
					(size 1.27 1.27)
					(thickness 0.15)
				)
				(justify left bottom)
				(hide yes)
			)
		)
		(property "Footprint" "antmicro-footprints:C_0402_1005Metric"
			(at 133.35 167.64 0)
			(effects
				(font
					(size 1.27 1.27)
					(thickness 0.15)
				)
				(justify left bottom)
				(hide yes)
			)
		)
		(property "Datasheet" "https://www.murata.com/products/productdetail?partno=GRM155R61H104KE14%23"
			(at 130.81 167.64 0)
			(effects
				(font
					(size 1.27 1.27)
					(thickness 0.15)
				)
				(justify left bottom)
				(hide yes)
			)
		)
		(property "Description" "SMD Multilayer Ceramic Capacitor, 0.1 µF, 50 V, 0402 [1005 Metric], ± 10%, X5R, GRM Series"
			(at 146.05 187.96 0)
			(effects
				(font
					(size 1.27 1.27)
				)
				(hide yes)
			)
		)
		(property "MPN" "GRM155R61H104KE14D"
			(at 128.27 167.64 0)
			(effects
				(font
					(size 1.27 1.27)
					(thickness 0.15)
				)
				(justify left bottom)
				(hide yes)
			)
		)
		(property "Manufacturer" "Murata"
			(at 125.73 167.64 0)
			(effects
				(font
					(size 1.27 1.27)
					(thickness 0.15)
				)
				(justify left bottom)
				(hide yes)
			)
		)
		(property "License" "Apache-2.0"
			(at 123.19 167.64 0)
			(effects
				(font
					(size 1.27 1.27)
					(thickness 0.15)
				)
				(justify left bottom)
				(hide yes)
			)
		)
		(property "Author" "Antmicro"
			(at 120.65 167.64 0)
			(effects
				(font
					(size 1.27 1.27)
					(thickness 0.15)
				)
				(justify left bottom)
				(hide yes)
			)
		)
		(property "Val" "100n"
			(at 143.51 186.6836 90)
			(effects
				(font
					(size 1.27 1.27)
					(thickness 0.15)
				)
				(justify right)
			)
		)
		(property "Voltage" "50V"
			(at 118.11 167.64 0)
			(effects
				(font
					(size 1.27 1.27)
				)
				(justify left bottom)
				(hide yes)
			)
		)
		(property "Dielectric" "X5R"
			(at 115.57 167.64 0)
			(effects
				(font
					(size 1.27 1.27)
				)
				(justify left bottom)
				(hide yes)
			)
		)
		(property "Public" "False"
			(at 113.03 167.64 0)
			(effects
				(font
					(size 1.27 1.27)
				)
				(justify left bottom)
				(hide yes)
			)
		)
		(pin "1"
		)
		(pin "2"
		)
		(instances
			(project "jetson-orin-baseboard-oculink-expansion"
				(path ""
					(reference "C28")
					(unit 1)
				)
			)
		)
	)
	(symbol
		(lib_id "antmicroResistors0402:R_1k_0402")
		(at 157.48 130.81 90)
		(unit 1)
		(exclude_from_sim no)
		(in_bom yes)
		(on_board yes)
		(dnp no)
		(property "Reference" "R26"
			(at 157.48 134.62 0)
			(effects
				(font
					(size 1.27 1.27)
					(thickness 0.15)
				)
				(justify right)
			)
		)
		(property "Value" "R_1k_0402"
			(at 170.18 110.49 0)
			(effects
				(font
					(size 1.27 1.27)
					(thickness 0.15)
				)
				(justify left bottom)
				(hide yes)
			)
		)
		(property "Footprint" "antmicro-footprints:R_0402_1005Metric"
			(at 172.72 110.49 0)
			(effects
				(font
					(size 1.27 1.27)
					(thickness 0.15)
				)
				(justify left bottom)
				(hide yes)
			)
		)
		(property "Datasheet" "https://www.bourns.com/docs/product-datasheets/cr.pdf"
			(at 175.26 110.49 0)
			(effects
				(font
					(size 1.27 1.27)
					(thickness 0.15)
				)
				(justify left bottom)
				(hide yes)
			)
		)
		(property "Description" "SMD Chip Resistor, 1 kohm, ± 1%, 63 mW, 0402 [1005 Metric], Thick Film, General Purpose"
			(at 157.48 130.81 0)
			(effects
				(font
					(size 1.27 1.27)
				)
				(hide yes)
			)
		)
		(property "MPN" "CR0402-FX-1001GLF"
			(at 177.8 110.49 0)
			(effects
				(font
					(size 1.27 1.27)
					(thickness 0.15)
				)
				(justify left bottom)
				(hide yes)
			)
		)
		(property "Manufacturer" "Bourns"
			(at 180.34 110.49 0)
			(effects
				(font
					(size 1.27 1.27)
					(thickness 0.15)
				)
				(justify left bottom)
				(hide yes)
			)
		)
		(property "License" "Apache-2.0"
			(at 182.88 110.49 0)
			(effects
				(font
					(size 1.27 1.27)
					(thickness 0.15)
				)
				(justify left bottom)
				(hide yes)
			)
		)
		(property "Author" "Antmicro"
			(at 185.42 110.49 0)
			(effects
				(font
					(size 1.27 1.27)
					(thickness 0.15)
				)
				(justify left bottom)
				(hide yes)
			)
		)
		(property "Val" "1k"
			(at 156.21 130.81 0)
			(effects
				(font
					(size 1.27 1.27)
					(thickness 0.15)
				)
				(justify right)
			)
		)
		(property "Tolerance" "1%"
			(at 167.64 110.49 0)
			(effects
				(font
					(size 1.27 1.27)
				)
				(justify left bottom)
				(hide yes)
			)
		)
		(property "Public" "False"
			(at 187.96 110.49 0)
			(effects
				(font
					(size 1.27 1.27)
				)
				(justify left bottom)
				(hide yes)
			)
		)
		(pin "1"
		)
		(pin "2"
		)
		(instances
			(project "jetson-orin-baseboard-oculink-expansion"
				(path ""
					(reference "R26")
					(unit 1)
				)
			)
		)
	)
	(symbol
		(lib_id "antmicropower:+5V")
		(at 44.45 128.27 0)
		(unit 1)
		(exclude_from_sim no)
		(in_bom yes)
		(on_board yes)
		(dnp no)
		(property "Reference" "#PWR04"
			(at 59.69 130.81 0)
			(effects
				(font
					(size 1.27 1.27)
					(thickness 0.15)
				)
				(justify left bottom)
				(hide yes)
			)
		)
		(property "Value" "+5V"
			(at 44.704 124.46 0)
			(effects
				(font
					(size 1.27 1.27)
					(thickness 0.15)
				)
			)
		)
		(property "Footprint" ""
			(at 59.69 135.89 0)
			(effects
				(font
					(size 1.27 1.27)
					(thickness 0.15)
				)
				(justify left bottom)
				(hide yes)
			)
		)
		(property "Datasheet" ""
			(at 59.69 138.43 0)
			(effects
				(font
					(size 1.27 1.27)
					(thickness 0.15)
				)
				(justify left bottom)
				(hide yes)
			)
		)
		(property "Description" ""
			(at 44.45 128.27 0)
			(effects
				(font
					(size 1.27 1.27)
				)
				(hide yes)
			)
		)
		(property "Author" "Antmicro"
			(at 59.69 135.89 0)
			(effects
				(font
					(size 1.27 1.27)
					(thickness 0.15)
				)
				(justify left bottom)
				(hide yes)
			)
		)
		(property "License" "Apache-2.0"
			(at 59.69 138.43 0)
			(effects
				(font
					(size 1.27 1.27)
					(thickness 0.15)
				)
				(justify left bottom)
				(hide yes)
			)
		)
		(pin "1"
		)
		(instances
			(project ""
				(path ""
					(reference "#PWR04")
					(unit 1)
				)
			)
		)
	)
	(symbol
		(lib_id "antmicroResistors0402:R_10k_0402")
		(at 246.38 242.57 90)
		(unit 1)
		(exclude_from_sim no)
		(in_bom yes)
		(on_board yes)
		(dnp no)
		(property "Reference" "R31"
			(at 248.92 237.998 0)
			(effects
				(font
					(size 1.27 1.27)
					(thickness 0.15)
				)
				(justify right)
			)
		)
		(property "Value" "R_10k_0402"
			(at 259.08 222.25 0)
			(effects
				(font
					(size 1.27 1.27)
					(thickness 0.15)
				)
				(justify left bottom)
				(hide yes)
			)
		)
		(property "Footprint" "antmicro-footprints:R_0402_1005Metric"
			(at 261.62 222.25 0)
			(effects
				(font
					(size 1.27 1.27)
					(thickness 0.15)
				)
				(justify left bottom)
				(hide yes)
			)
		)
		(property "Datasheet" "https://www.bourns.com/docs/product-datasheets/cr.pdf"
			(at 264.16 222.25 0)
			(effects
				(font
					(size 1.27 1.27)
					(thickness 0.15)
				)
				(justify left bottom)
				(hide yes)
			)
		)
		(property "Description" "SMD Chip Resistor, 10 kohm, ± 1%, 62.5 mW, 0402 [1005 Metric], Thick Film, General Purpose"
			(at 246.38 242.57 0)
			(effects
				(font
					(size 1.27 1.27)
				)
				(hide yes)
			)
		)
		(property "MPN" "CR0402-FX-1002GLF"
			(at 266.7 222.25 0)
			(effects
				(font
					(size 1.27 1.27)
					(thickness 0.15)
				)
				(justify left bottom)
				(hide yes)
			)
		)
		(property "Manufacturer" "Bourns"
			(at 269.24 222.25 0)
			(effects
				(font
					(size 1.27 1.27)
					(thickness 0.15)
				)
				(justify left bottom)
				(hide yes)
			)
		)
		(property "License" "Apache-2.0"
			(at 271.78 222.25 0)
			(effects
				(font
					(size 1.27 1.27)
					(thickness 0.15)
				)
				(justify left bottom)
				(hide yes)
			)
		)
		(property "Author" "Antmicro"
			(at 274.32 222.25 0)
			(effects
				(font
					(size 1.27 1.27)
					(thickness 0.15)
				)
				(justify left bottom)
				(hide yes)
			)
		)
		(property "Val" "10k"
			(at 250.698 238.252 0)
			(effects
				(font
					(size 1.27 1.27)
					(thickness 0.15)
				)
				(justify right)
			)
		)
		(property "Tolerance" "1%"
			(at 256.54 222.25 0)
			(effects
				(font
					(size 1.27 1.27)
				)
				(justify left bottom)
				(hide yes)
			)
		)
		(pin "2"
		)
		(pin "1"
		)
		(instances
			(project "jetson-orin-baseboard-oculink-expansion"
				(path ""
					(reference "R31")
					(unit 1)
				)
			)
		)
	)
	(symbol
		(lib_id "antmicroResistors0402:R_0R_0402")
		(at 229.87 99.06 180)
		(unit 1)
		(exclude_from_sim no)
		(in_bom yes)
		(on_board yes)
		(dnp no)
		(property "Reference" "R32"
			(at 227.33 101.6 0)
			(effects
				(font
					(size 1.27 1.27)
					(thickness 0.15)
				)
			)
		)
		(property "Value" "R_0R_0402"
			(at 209.55 86.36 0)
			(effects
				(font
					(size 1.27 1.27)
					(thickness 0.15)
				)
				(justify left bottom)
				(hide yes)
			)
		)
		(property "Footprint" "antmicro-footprints:R_0402_1005Metric"
			(at 209.55 83.82 0)
			(effects
				(font
					(size 1.27 1.27)
					(thickness 0.15)
				)
				(justify left bottom)
				(hide yes)
			)
		)
		(property "Datasheet" "https://industrial.panasonic.com/cdbs/www-data/pdf/RDA0000/AOA0000C301.pdf"
			(at 209.55 81.28 0)
			(effects
				(font
					(size 1.27 1.27)
					(thickness 0.15)
				)
				(justify left bottom)
				(hide yes)
			)
		)
		(property "Description" "SMD Chip Resistor, Jumper, 0 ohm, 100 mW, 0402 [1005 Metric], Thick Film, General Purpose"
			(at 229.87 99.06 0)
			(effects
				(font
					(size 1.27 1.27)
				)
				(hide yes)
			)
		)
		(property "MPN" "ERJ2GE0R00X"
			(at 209.55 78.74 0)
			(effects
				(font
					(size 1.27 1.27)
					(thickness 0.15)
				)
				(justify left bottom)
				(hide yes)
			)
		)
		(property "Manufacturer" "Panasonic"
			(at 209.55 76.2 0)
			(effects
				(font
					(size 1.27 1.27)
					(thickness 0.15)
				)
				(justify left bottom)
				(hide yes)
			)
		)
		(property "License" "Apache-2.0"
			(at 209.55 73.66 0)
			(effects
				(font
					(size 1.27 1.27)
					(thickness 0.15)
				)
				(justify left bottom)
				(hide yes)
			)
		)
		(property "Author" "Antmicro"
			(at 209.55 71.12 0)
			(effects
				(font
					(size 1.27 1.27)
					(thickness 0.15)
				)
				(justify left bottom)
				(hide yes)
			)
		)
		(property "Val" "0R"
			(at 227.33 104.14 0)
			(effects
				(font
					(size 1.27 1.27)
					(thickness 0.15)
				)
			)
		)
		(property "Tolerance" "~"
			(at 209.55 88.9 0)
			(effects
				(font
					(size 1.27 1.27)
				)
				(justify left bottom)
				(hide yes)
			)
		)
		(property "Current" "1A"
			(at 209.55 68.58 0)
			(effects
				(font
					(size 1.27 1.27)
					(thickness 0.15)
				)
				(justify left bottom)
				(hide yes)
			)
		)
		(property "Public" "False"
			(at 209.55 68.58 0)
			(effects
				(font
					(size 1.27 1.27)
				)
				(justify left bottom)
				(hide yes)
			)
		)
		(pin "1"
		)
		(pin "2"
		)
		(instances
			(project "jetson-orin-baseboard-oculink-expansion"
				(path ""
					(reference "R32")
					(unit 1)
				)
			)
		)
	)
	(symbol
		(lib_id "antmicropower:GND")
		(at 246.38 243.84 0)
		(unit 1)
		(exclude_from_sim no)
		(in_bom yes)
		(on_board yes)
		(dnp no)
		(property "Reference" "#PWR059"
			(at 255.27 246.38 0)
			(effects
				(font
					(size 1.27 1.27)
					(thickness 0.15)
				)
				(justify left bottom)
				(hide yes)
			)
		)
		(property "Value" "GND"
			(at 250.19 245.11 0)
			(effects
				(font
					(size 1.27 1.27)
					(thickness 0.15)
				)
			)
		)
		(property "Footprint" ""
			(at 255.27 251.46 0)
			(effects
				(font
					(size 1.27 1.27)
					(thickness 0.15)
				)
				(justify left bottom)
				(hide yes)
			)
		)
		(property "Datasheet" ""
			(at 255.27 256.54 0)
			(effects
				(font
					(size 1.27 1.27)
					(thickness 0.15)
				)
				(justify left bottom)
				(hide yes)
			)
		)
		(property "Description" ""
			(at 246.38 243.84 0)
			(effects
				(font
					(size 1.27 1.27)
				)
				(hide yes)
			)
		)
		(property "Author" "Antmicro"
			(at 255.27 251.46 0)
			(effects
				(font
					(size 1.27 1.27)
					(thickness 0.15)
				)
				(justify left bottom)
				(hide yes)
			)
		)
		(property "License" "Apache-2.0"
			(at 255.27 254 0)
			(effects
				(font
					(size 1.27 1.27)
					(thickness 0.15)
				)
				(justify left bottom)
				(hide yes)
			)
		)
		(pin "1"
		)
		(instances
			(project "jetson-orin-baseboard-oculink-expansion"
				(path ""
					(reference "#PWR059")
					(unit 1)
				)
			)
		)
	)
	(symbol
		(lib_id "antmicroTestPoints:TP_1.5mm_SMD")
		(at 304.8 50.8 180)
		(unit 1)
		(exclude_from_sim no)
		(in_bom no)
		(on_board yes)
		(dnp no)
		(property "Reference" "TP1"
			(at 298.958 50.8 0)
			(effects
				(font
					(size 1.27 1.27)
					(thickness 0.15)
				)
			)
		)
		(property "Value" "TP_1.5mm_SMD"
			(at 289.56 43.18 0)
			(effects
				(font
					(size 1.27 1.27)
					(thickness 0.15)
				)
				(justify left bottom)
				(hide yes)
			)
		)
		(property "Footprint" "antmicro-footprints:TP_SMD_1.5mm"
			(at 289.56 40.64 0)
			(effects
				(font
					(size 1.27 1.27)
					(thickness 0.15)
				)
				(justify left bottom)
				(hide yes)
			)
		)
		(property "Datasheet" ""
			(at 287.02 38.1 0)
			(effects
				(font
					(size 1.27 1.27)
					(thickness 0.15)
				)
				(justify left bottom)
				(hide yes)
			)
		)
		(property "Description" "test point, SMT"
			(at 304.8 50.8 0)
			(effects
				(font
					(size 1.27 1.27)
				)
				(hide yes)
			)
		)
		(property "MPN" ""
			(at 304.8 50.8 0)
			(effects
				(font
					(size 1.27 1.27)
				)
				(hide yes)
			)
		)
		(property "Manufacturer" ""
			(at 304.8 50.8 0)
			(effects
				(font
					(size 1.27 1.27)
				)
				(hide yes)
			)
		)
		(property "Author" "Antmicro"
			(at 289.56 35.56 0)
			(effects
				(font
					(size 1.27 1.27)
					(thickness 0.15)
				)
				(justify left bottom)
				(hide yes)
			)
		)
		(property "License" "Apache-2.0"
			(at 289.56 33.02 0)
			(effects
				(font
					(size 1.27 1.27)
					(thickness 0.15)
				)
				(justify left bottom)
				(hide yes)
			)
		)
		(pin "1"
		)
		(instances
			(project "jetson-orin-baseboard-oculink-expansion"
				(path ""
					(reference "TP1")
					(unit 1)
				)
			)
		)
	)
	(symbol
		(lib_id "antmicroMechanicalParts:MP_Pad5.4mm_Drill2.7mm")
		(at 341.63 241.3 180)
		(unit 1)
		(exclude_from_sim no)
		(in_bom no)
		(on_board yes)
		(dnp no)
		(fields_autoplaced yes)
		(property "Reference" "MP2"
			(at 336.55 233.68 0)
			(effects
				(font
					(size 1.27 1.27)
					(thickness 0.15)
				)
			)
		)
		(property "Value" "MP_Pad5.4mm_Drill2.7mm"
			(at 336.55 236.22 0)
			(effects
				(font
					(size 1.27 1.27)
					(thickness 0.15)
				)
			)
		)
		(property "Footprint" "antmicro-footprints:MP_Pad5.4mm_Drill2.7mm"
			(at 321.31 233.68 0)
			(effects
				(font
					(size 1.27 1.27)
					(thickness 0.15)
				)
				(justify left bottom)
				(hide yes)
			)
		)
		(property "Datasheet" ""
			(at 324.79 225.73 0)
			(effects
				(font
					(size 1.27 1.27)
					(thickness 0.15)
				)
				(justify left bottom)
				(hide yes)
			)
		)
		(property "Description" "Mechanical part"
			(at 341.63 241.3 0)
			(effects
				(font
					(size 1.27 1.27)
				)
				(hide yes)
			)
		)
		(property "Author" "Antmicro"
			(at 321.31 231.14 0)
			(effects
				(font
					(size 1.27 1.27)
					(thickness 0.15)
				)
				(justify left bottom)
				(hide yes)
			)
		)
		(property "License" "Apache-2.0"
			(at 321.31 228.6 0)
			(effects
				(font
					(size 1.27 1.27)
					(thickness 0.15)
				)
				(justify left bottom)
				(hide yes)
			)
		)
		(pin "1"
		)
		(instances
			(project "jetson-orin-baseboard-oculink-expansion"
				(path ""
					(reference "MP2")
					(unit 1)
				)
			)
		)
	)
	(symbol
		(lib_id "antmicroResistors0402:R_1k_0402")
		(at 160.02 130.81 90)
		(unit 1)
		(exclude_from_sim no)
		(in_bom yes)
		(on_board yes)
		(dnp yes)
		(property "Reference" "R28"
			(at 160.02 134.62 0)
			(effects
				(font
					(size 1.27 1.27)
					(thickness 0.15)
				)
				(justify right)
			)
		)
		(property "Value" "R_1k_0402"
			(at 172.72 110.49 0)
			(effects
				(font
					(size 1.27 1.27)
					(thickness 0.15)
				)
				(justify left bottom)
				(hide yes)
			)
		)
		(property "Footprint" "antmicro-footprints:R_0402_1005Metric"
			(at 175.26 110.49 0)
			(effects
				(font
					(size 1.27 1.27)
					(thickness 0.15)
				)
				(justify left bottom)
				(hide yes)
			)
		)
		(property "Datasheet" "https://www.bourns.com/docs/product-datasheets/cr.pdf"
			(at 177.8 110.49 0)
			(effects
				(font
					(size 1.27 1.27)
					(thickness 0.15)
				)
				(justify left bottom)
				(hide yes)
			)
		)
		(property "Description" "SMD Chip Resistor, 1 kohm, ± 1%, 63 mW, 0402 [1005 Metric], Thick Film, General Purpose"
			(at 160.02 130.81 0)
			(effects
				(font
					(size 1.27 1.27)
				)
				(hide yes)
			)
		)
		(property "MPN" "CR0402-FX-1001GLF"
			(at 180.34 110.49 0)
			(effects
				(font
					(size 1.27 1.27)
					(thickness 0.15)
				)
				(justify left bottom)
				(hide yes)
			)
		)
		(property "Manufacturer" "Bourns"
			(at 182.88 110.49 0)
			(effects
				(font
					(size 1.27 1.27)
					(thickness 0.15)
				)
				(justify left bottom)
				(hide yes)
			)
		)
		(property "License" "Apache-2.0"
			(at 185.42 110.49 0)
			(effects
				(font
					(size 1.27 1.27)
					(thickness 0.15)
				)
				(justify left bottom)
				(hide yes)
			)
		)
		(property "Author" "Antmicro"
			(at 187.96 110.49 0)
			(effects
				(font
					(size 1.27 1.27)
					(thickness 0.15)
				)
				(justify left bottom)
				(hide yes)
			)
		)
		(property "Val" "1k"
			(at 158.75 130.81 0)
			(effects
				(font
					(size 1.27 1.27)
					(thickness 0.15)
				)
				(justify right)
			)
		)
		(property "Tolerance" "1%"
			(at 170.18 110.49 0)
			(effects
				(font
					(size 1.27 1.27)
				)
				(justify left bottom)
				(hide yes)
			)
		)
		(property "Public" "False"
			(at 190.5 110.49 0)
			(effects
				(font
					(size 1.27 1.27)
				)
				(justify left bottom)
				(hide yes)
			)
		)
		(pin "1"
		)
		(pin "2"
		)
		(instances
			(project "jetson-orin-baseboard-oculink-expansion"
				(path ""
					(reference "R28")
					(unit 1)
				)
			)
		)
	)
	(symbol
		(lib_id "antmicroCapacitorsmisc:C_100u_0805")
		(at 298.45 130.81 90)
		(unit 1)
		(exclude_from_sim no)
		(in_bom yes)
		(on_board yes)
		(dnp no)
		(property "Reference" "C32"
			(at 300.482 127 90)
			(effects
				(font
					(size 1.27 1.27)
					(thickness 0.15)
				)
				(justify right)
			)
		)
		(property "Value" "C_100u_0805"
			(at 308.61 110.49 0)
			(effects
				(font
					(size 1.27 1.27)
					(thickness 0.15)
				)
				(justify left bottom)
				(hide yes)
			)
		)
		(property "Footprint" "antmicro-footprints:C_0805_2012Metric"
			(at 311.15 110.49 0)
			(effects
				(font
					(size 1.27 1.27)
					(thickness 0.15)
				)
				(justify left bottom)
				(hide yes)
			)
		)
		(property "Datasheet" "https://www.murata.com/products/productdetail?partno=GRM21BR60J107ME15%23"
			(at 313.69 110.49 0)
			(effects
				(font
					(size 1.27 1.27)
					(thickness 0.15)
				)
				(justify left bottom)
				(hide yes)
			)
		)
		(property "Description" "SMD Multilayer Ceramic Capacitor, 100 µF, 6.3 V, 0805 [2012 Metric], ± 20%, X5R, GRM Series"
			(at 298.45 130.81 0)
			(effects
				(font
					(size 1.27 1.27)
				)
				(hide yes)
			)
		)
		(property "MPN" "GRM21BR60J107ME15L"
			(at 316.23 110.49 0)
			(effects
				(font
					(size 1.27 1.27)
					(thickness 0.15)
				)
				(justify left bottom)
				(hide yes)
			)
		)
		(property "Manufacturer" "Murata"
			(at 318.77 110.49 0)
			(effects
				(font
					(size 1.27 1.27)
					(thickness 0.15)
				)
				(justify left bottom)
				(hide yes)
			)
		)
		(property "License" "Apache-2.0"
			(at 321.31 110.49 0)
			(effects
				(font
					(size 1.27 1.27)
					(thickness 0.15)
				)
				(justify left bottom)
				(hide yes)
			)
		)
		(property "Author" "Antmicro"
			(at 323.85 110.49 0)
			(effects
				(font
					(size 1.27 1.27)
					(thickness 0.15)
				)
				(justify left bottom)
				(hide yes)
			)
		)
		(property "Val" "100u"
			(at 300.482 129.54 90)
			(effects
				(font
					(size 1.27 1.27)
					(thickness 0.15)
				)
				(justify right)
			)
		)
		(property "Voltage" ""
			(at 326.39 110.49 0)
			(effects
				(font
					(size 1.27 1.27)
				)
				(justify left bottom)
				(hide yes)
			)
		)
		(property "Dielectric" ""
			(at 328.93 110.49 0)
			(effects
				(font
					(size 1.27 1.27)
				)
				(justify left bottom)
				(hide yes)
			)
		)
		(property "Public" "False"
			(at 331.47 110.49 0)
			(effects
				(font
					(size 1.27 1.27)
				)
				(justify left bottom)
				(hide yes)
			)
		)
		(pin "2"
		)
		(pin "1"
		)
		(instances
			(project ""
				(path ""
					(reference "C32")
					(unit 1)
				)
			)
		)
	)
	(sheet_instances
		(path "/"
			(page "1")
		)
	)
)
